%FSTAX25Y25*%
%MOIN*%
%SFA1B1*%

%IPPOS*%
%ADD140C,0.120000*%
%ADD155C,0.075000*%
%ADD156C,0.098430*%
%ADD158O,0.177170X0.088580*%
%ADD159O,0.088580X0.177170*%
%ADD165C,0.016000*%
%LNgrandmaster-1*%
%LPD*%
G36*
X13389Y05513D02*
X09105D01*
Y0522933*
X08285*
Y05318*
X08253Y0535*
X08225*
X08193Y05318*
Y0522933*
X07772*
Y0534515*
X0777459Y0534649*
X07777Y0534711*
X0778176Y0534393*
X07788Y0534269*
X0779424Y0534393*
X0779953Y0534747*
X0780307Y0535276*
X0780431Y05359*
X0780307Y0536524*
X0779953Y0537053*
X0779424Y0537407*
X07788Y0537531*
X0778176Y0537407*
X07777Y0537089*
X0777459Y0537151*
X07772Y0537285*
Y05473*
X07726Y05519*
X07654*
X07609Y05474*
Y0531788*
X07312*
Y05516*
X06572*
Y05192*
X05998*
Y09358*
X06001Y09361*
X13389*
Y05513*
G37*
%LNgrandmaster-2*%
%LPC*%
G36*
X08561Y0930331D02*
X0855476Y0930207D01*
X0854947Y0929854*
X0854593Y0929324*
X0854469Y09287*
X0854593Y0928076*
X0854947Y0927547*
X0855476Y0927193*
X08561Y0927069*
X0856724Y0927193*
X0857253Y0927547*
X0857607Y0928076*
X0857731Y09287*
X0857607Y0929324*
X0857253Y0929854*
X0856724Y0930207*
X08561Y0930331*
G37*
G36*
X07285Y0927631D02*
X0727876Y0927507D01*
X0727347Y0927153*
X0726993Y0926624*
X0726869Y0926*
X0726993Y0925376*
X0727347Y0924846*
X0727876Y0924493*
X07285Y0924369*
X0729124Y0924493*
X0729654Y0924846*
X0730007Y0925376*
X0730131Y0926*
X0730007Y0926624*
X0729654Y0927153*
X0729124Y0927507*
X07285Y0927631*
G37*
G36*
X074645Y092995D02*
X073935D01*
Y092285*
X074645*
Y092995*
G37*
G36*
X080655Y092915D02*
X079945D01*
Y092205*
X080655*
Y092915*
G37*
G36*
X07548Y0924931D02*
X0754176Y0924807D01*
X0753647Y0924454*
X0753293Y0923924*
X0753169Y09233*
X0753293Y0922676*
X0753647Y0922147*
X0754176Y0921793*
X07548Y0921669*
X0755424Y0921793*
X0755954Y0922147*
X0756307Y0922676*
X0756431Y09233*
X0756307Y0923924*
X0755954Y0924454*
X0755424Y0924807*
X07548Y0924931*
G37*
G36*
X0777Y0917631D02*
X0776376Y0917507D01*
X0775846Y0917153*
X0775493Y0916624*
X0775369Y0916*
X0775493Y0915376*
X0775846Y0914847*
X0776376Y0914493*
X0777Y0914369*
X0777624Y0914493*
X0778154Y0914847*
X0778507Y0915376*
X0778631Y0916*
X0778507Y0916624*
X0778154Y0917153*
X0777624Y0917507*
X0777Y0917631*
G37*
G36*
X07429Y0919981D02*
X0741973Y0919859D01*
X074111Y0919501*
X0740368Y0918932*
X0739799Y091819*
X0739441Y0917327*
X0739319Y09164*
X0739441Y0915473*
X0739799Y091461*
X0740368Y0913868*
X074111Y0913299*
X0741973Y0912941*
X07429Y0912819*
X0743827Y0912941*
X074469Y0913299*
X0745432Y0913868*
X0746001Y091461*
X0746359Y0915473*
X0746481Y09164*
X0746359Y0917327*
X0746001Y091819*
X0745432Y0918932*
X074469Y0919501*
X0743827Y0919859*
X07429Y0919981*
G37*
G36*
X0803Y0919181D02*
X0802073Y0919059D01*
X080121Y0918701*
X0800468Y0918132*
X0799899Y091739*
X0799541Y0916527*
X0799419Y09156*
X0799541Y0914673*
X0799899Y091381*
X0800468Y0913068*
X080121Y0912499*
X0802073Y0912141*
X0803Y0912019*
X0803927Y0912141*
X080479Y0912499*
X0805532Y0913068*
X0806101Y091381*
X0806459Y0914673*
X0806581Y09156*
X0806459Y0916527*
X0806101Y091739*
X0805532Y0918132*
X080479Y0918701*
X0803927Y0919059*
X0803Y0919181*
G37*
G36*
X07576Y0914531D02*
X0756976Y0914407D01*
X0756447Y0914054*
X0756093Y0913524*
X0755969Y09129*
X0756093Y0912276*
X0756447Y0911747*
X0756976Y0911393*
X07576Y0911269*
X0758224Y0911393*
X0758753Y0911747*
X0759107Y0912276*
X0759231Y09129*
X0759107Y0913524*
X0758753Y0914054*
X0758224Y0914407*
X07576Y0914531*
G37*
G36*
X0994823Y0915594D02*
X0994151Y0915506D01*
X0993526Y0915246*
X0992989Y0914834*
X0992577Y0914297*
X0992317Y0913671*
X0992229Y0913*
X0992317Y0912329*
X0992577Y0911703*
X0992989Y0911166*
X0993526Y0910754*
X0994151Y0910495*
X0994823Y0910406*
X0995494Y0910495*
X099612Y0910754*
X0996657Y0911166*
X0997069Y0911703*
X0997328Y0912329*
X0997417Y0913*
X0997328Y0913671*
X0997069Y0914297*
X0996657Y0914834*
X099612Y0915246*
X0995494Y0915506*
X0994823Y0915594*
G37*
G36*
X09775D02*
X0976829Y0915506D01*
X0976203Y0915246*
X0975666Y0914834*
X0975254Y0914297*
X0974994Y0913671*
X0974906Y0913*
X0974994Y0912329*
X0975254Y0911703*
X0975666Y0911166*
X0976203Y0910754*
X0976829Y0910495*
X09775Y0910406*
X0978171Y0910495*
X0978797Y0910754*
X0979334Y0911166*
X0979746Y0911703*
X0980005Y0912329*
X0980094Y0913*
X0980005Y0913671*
X0979746Y0914297*
X0979334Y0914834*
X0978797Y0915246*
X0978171Y0915506*
X09775Y0915594*
G37*
G36*
X1074487Y0913618D02*
X1073863Y0913494D01*
X1073333Y091314*
X107298Y0912611*
X1072856Y0911987*
X107298Y0911363*
X1073333Y0910833*
X1073863Y091048*
X1074487Y0910356*
X1075111Y091048*
X107564Y0910833*
X1075994Y0911363*
X1076118Y0911987*
X1075994Y0912611*
X107564Y091314*
X1075111Y0913494*
X1074487Y0913618*
G37*
G36*
X117122Y0919881D02*
X1169727Y0919684D01*
X1168335Y0919108*
X116714Y0918191*
X1166223Y0916996*
X1165646Y0915604*
X116545Y091411*
X1165646Y0912617*
X1166223Y0911225*
X116714Y091003*
X1168335Y0909113*
X1169727Y0908536*
X117122Y090834*
X1172714Y0908536*
X1174106Y0909113*
X1175301Y091003*
X1176218Y0911225*
X1176795Y0912617*
X1176991Y091411*
X1176795Y0915604*
X1176218Y0916996*
X1175301Y0918191*
X1174106Y0919108*
X1172714Y0919684*
X117122Y0919881*
G37*
G36*
X1125716Y0910915D02*
X1125092Y0910791D01*
X1124563Y0910437*
X1124209Y0909908*
X1124085Y0909284*
X1124209Y0908659*
X1124563Y090813*
X1125092Y0907776*
X1125716Y0907652*
X1126341Y0907776*
X112687Y090813*
X1127224Y0908659*
X1127348Y0909284*
X1127224Y0909908*
X112687Y0910437*
X1126341Y0910791*
X1125716Y0910915*
G37*
G36*
X09495Y0910631D02*
X0948876Y0910507D01*
X0948347Y0910153*
X0947993Y0909624*
X0947869Y0909*
X0947993Y0908376*
X0948347Y0907847*
X0948876Y0907493*
X09495Y0907369*
X0950124Y0907493*
X0950653Y0907847*
X0951007Y0908376*
X0951131Y0909*
X0951007Y0909624*
X0950653Y0910153*
X0950124Y0910507*
X09495Y0910631*
G37*
G36*
X09285Y0913138D02*
X092743Y0912998D01*
X0926433Y0912585*
X0925576Y0911928*
X0924919Y0911071*
X0924506Y0910074*
X0924365Y0909004*
X0924506Y0907934*
X0924919Y0906937*
X0925576Y090608*
X0926433Y0905423*
X092743Y090501*
X09285Y0904869*
X092957Y090501*
X0930567Y0905423*
X0931424Y090608*
X0932081Y0906937*
X0932494Y0907934*
X0932635Y0909004*
X0932494Y0910074*
X0932081Y0911071*
X0931424Y0911928*
X0930567Y0912585*
X092957Y0912998*
X09285Y0913138*
G37*
G36*
X08985D02*
X089743Y0912998D01*
X0896433Y0912585*
X0895576Y0911928*
X0894919Y0911071*
X0894506Y0910074*
X0894365Y0909004*
X0894506Y0907934*
X0894919Y0906937*
X0895576Y090608*
X0896433Y0905423*
X089743Y090501*
X08985Y0904869*
X089957Y090501*
X0900567Y0905423*
X0901424Y090608*
X0902081Y0906937*
X0902494Y0907934*
X0902635Y0909004*
X0902494Y0910074*
X0902081Y0911071*
X0901424Y0911928*
X0900567Y0912585*
X089957Y0912998*
X08985Y0913138*
G37*
G36*
X13206Y0930141D02*
X1318513Y0929977D01*
X1316477Y0929488*
X1314543Y0928687*
X1312758Y0927593*
X1311166Y0926234*
X1309807Y0924642*
X1308713Y0922857*
X1307912Y0920923*
X1307423Y0918887*
X1307259Y09168*
X1307423Y0914713*
X1307912Y0912677*
X1308713Y0910743*
X1309807Y0908958*
X1311166Y0907366*
X1312758Y0906007*
X1314543Y0904913*
X1316477Y0904112*
X1318513Y0903623*
X13206Y0903459*
X1322687Y0903623*
X1324723Y0904112*
X1326657Y0904913*
X1328442Y0906007*
X1330034Y0907366*
X1331393Y0908958*
X1332487Y0910743*
X1333288Y0912677*
X1333777Y0914713*
X1333941Y09168*
X1333777Y0918887*
X1333288Y0920923*
X1332487Y0922857*
X1331393Y0924642*
X1330034Y0926234*
X1328442Y0927593*
X1326657Y0928687*
X1324723Y0929488*
X1322687Y0929977*
X13206Y0930141*
G37*
G36*
X1289035Y0916478D02*
X1287721Y0916349D01*
X1286457Y0915965*
X1285292Y0915343*
X1284271Y0914505*
X1283433Y0913484*
X128281Y0912319*
X1282427Y0911055*
X1282298Y090974*
X1282427Y0908426*
X128281Y0907162*
X1283433Y0905997*
X1284271Y0904976*
X1285292Y0904138*
X1286457Y0903515*
X1287721Y0903132*
X1289035Y0903002*
X129035Y0903132*
X1291614Y0903515*
X1292779Y0904138*
X12938Y0904976*
X1294638Y0905997*
X1295261Y0907162*
X1295644Y0908426*
X1295773Y090974*
X1295644Y0911055*
X1295261Y0912319*
X1294638Y0913484*
X12938Y0914505*
X1292779Y0915343*
X1291614Y0915965*
X129035Y0916349*
X1289035Y0916478*
G37*
G36*
X1255965D02*
X125465Y0916349D01*
X1253386Y0915965*
X1252221Y0915343*
X12512Y0914505*
X1250362Y0913484*
X1249739Y0912319*
X1249356Y0911055*
X1249227Y090974*
X1249356Y0908426*
X1249739Y0907162*
X1250362Y0905997*
X12512Y0904976*
X1252221Y0904138*
X1253386Y0903515*
X125465Y0903132*
X1255965Y0903002*
X1257279Y0903132*
X1258543Y0903515*
X1259708Y0904138*
X1260729Y0904976*
X1261567Y0905997*
X126219Y0907162*
X1262573Y0908426*
X1262702Y090974*
X1262573Y0911055*
X126219Y0912319*
X1261567Y0913484*
X1260729Y0914505*
X1259708Y0915343*
X1258543Y0915965*
X1257279Y0916349*
X1255965Y0916478*
G37*
G36*
X07429Y0909981D02*
X0741973Y0909859D01*
X074111Y0909501*
X0740368Y0908932*
X0739799Y090819*
X0739441Y0907327*
X0739319Y09064*
X0739441Y0905473*
X0739799Y090461*
X0740368Y0903868*
X074111Y0903299*
X0741973Y0902941*
X07429Y0902819*
X0743827Y0902941*
X074469Y0903299*
X0745432Y0903868*
X0746001Y090461*
X0746359Y0905473*
X0746481Y09064*
X0746359Y0907327*
X0746001Y090819*
X0745432Y0908932*
X074469Y0909501*
X0743827Y0909859*
X07429Y0909981*
G37*
G36*
X06294Y0928941D02*
X0627313Y0928777D01*
X0625277Y0928288*
X0623343Y0927487*
X0621558Y0926393*
X0619966Y0925034*
X0618607Y0923442*
X0617513Y0921657*
X0616712Y0919723*
X0616223Y0917687*
X0616059Y09156*
X0616223Y0913513*
X0616712Y0911477*
X0617513Y0909543*
X0618607Y0907758*
X0619966Y0906166*
X0621558Y0904807*
X0623343Y0903713*
X0625277Y0902912*
X0627313Y0902423*
X06294Y0902259*
X0631487Y0902423*
X0633523Y0902912*
X0635457Y0903713*
X0637242Y0904807*
X0638834Y0906166*
X0640193Y0907758*
X0641287Y0909543*
X0642088Y0911477*
X0642577Y0913513*
X0642741Y09156*
X0642577Y0917687*
X0642088Y0919723*
X0641287Y0921657*
X0640193Y0923442*
X0638834Y0925034*
X0637242Y0926393*
X0635457Y0927487*
X0633523Y0928288*
X0631487Y0928777*
X06294Y0928941*
G37*
G36*
X0803Y0909181D02*
X0802073Y0909059D01*
X080121Y0908701*
X0800468Y0908132*
X0799899Y090739*
X0799541Y0906527*
X0799419Y09056*
X0799541Y0904673*
X0799899Y090381*
X0800468Y0903068*
X080121Y0902499*
X0802073Y0902141*
X0803Y0902019*
X0803927Y0902141*
X080479Y0902499*
X0805532Y0903068*
X0806101Y090381*
X0806459Y0904673*
X0806581Y09056*
X0806459Y0906527*
X0806101Y090739*
X0805532Y0908132*
X080479Y0908701*
X0803927Y0909059*
X0803Y0909181*
G37*
G36*
X07894Y0903831D02*
X0788776Y0903707D01*
X0788246Y0903354*
X0787893Y0902824*
X0787769Y09022*
X0787893Y0901576*
X0788246Y0901046*
X0788776Y0900693*
X07894Y0900569*
X0790024Y0900693*
X0790554Y0901046*
X0790907Y0901576*
X0791031Y09022*
X0790907Y0902824*
X0790554Y0903354*
X0790024Y0903707*
X07894Y0903831*
G37*
G36*
X08235Y0903731D02*
X0822876Y0903607D01*
X0822346Y0903253*
X0821993Y0902724*
X0821869Y09021*
X0821993Y0901476*
X0822346Y0900947*
X0822876Y0900593*
X08235Y0900469*
X0824124Y0900593*
X0824654Y0900947*
X0825007Y0901476*
X0825131Y09021*
X0825007Y0902724*
X0824654Y0903253*
X0824124Y0903607*
X08235Y0903731*
G37*
G36*
X117122Y0901771D02*
X1169727Y0901574D01*
X1168335Y0900998*
X116714Y090008*
X1166223Y0898885*
X1165646Y0897493*
X116545Y0896*
X1165646Y0894506*
X1166223Y0893115*
X116714Y089192*
X1168335Y0891002*
X1169727Y0890426*
X117122Y0890229*
X1172714Y0890426*
X1174106Y0891002*
X1175301Y089192*
X1176218Y0893115*
X1176795Y0894506*
X1176991Y0896*
X1176795Y0897493*
X1176218Y0898885*
X1175301Y090008*
X1174106Y0900998*
X1172714Y0901574*
X117122Y0901771*
G37*
G36*
X08075Y0891631D02*
X0806876Y0891507D01*
X0806347Y0891154*
X0805993Y0890624*
X0805869Y089*
X0805993Y0889376*
X0806009Y0889351*
X0805649Y0888991*
X0805624Y0889007*
X0805Y0889131*
X0804376Y0889007*
X0803846Y0888653*
X0803493Y0888124*
X0803369Y08875*
X0803493Y0886876*
X0803846Y0886347*
X0804376Y0885993*
X0805Y0885869*
X0805624Y0885993*
X0806153Y0886347*
X0806507Y0886876*
X0806631Y08875*
X0806507Y0888124*
X0806491Y0888149*
X0806851Y0888509*
X0806876Y0888493*
X08075Y0888369*
X0808124Y0888493*
X0808654Y0888846*
X0809007Y0889376*
X0809131Y089*
X0809007Y0890624*
X0808654Y0891154*
X0808124Y0891507*
X08075Y0891631*
G37*
G36*
X0802Y0885631D02*
X0801376Y0885507D01*
X0800846Y0885153*
X0800493Y0884624*
X0800369Y0884*
X0800383Y0883927*
X0800325Y0883832*
X079995Y0883542*
X07995Y0883631*
X0798876Y0883507*
X0798347Y0883154*
X0797993Y0882624*
X0797869Y0882*
X0797993Y0881376*
X0798347Y0880847*
X0798876Y0880493*
X07995Y0880369*
X0800124Y0880493*
X0800653Y0880847*
X0801007Y0881376*
X0801131Y0882*
X0801117Y0882073*
X0801175Y0882168*
X080155Y0882458*
X0802Y0882369*
X0802624Y0882493*
X0803154Y0882847*
X0803507Y0883376*
X0803631Y0884*
X0803507Y0884624*
X0803154Y0885153*
X0802624Y0885507*
X0802Y0885631*
G37*
G36*
X0969D02*
X0968376Y0885507D01*
X0967846Y0885153*
X0967493Y0884624*
X0967369Y0884*
X0967493Y0883376*
X0967846Y0882847*
X0968376Y0882493*
X0969Y0882369*
X0969624Y0882493*
X0970154Y0882847*
X0970507Y0883376*
X0970631Y0884*
X0970507Y0884624*
X0970154Y0885153*
X0969624Y0885507*
X0969Y0885631*
G37*
G36*
X09005Y0885131D02*
X0899876Y0885007D01*
X0899347Y0884653*
X0898993Y0884124*
X0898869Y08835*
X0898993Y0882876*
X0899347Y0882347*
X0899876Y0881993*
X09005Y0881869*
X0901124Y0881993*
X0901653Y0882347*
X0902007Y0882876*
X0902131Y08835*
X0902007Y0884124*
X0901653Y0884653*
X0901124Y0885007*
X09005Y0885131*
G37*
G36*
X0982Y0882631D02*
X0981376Y0882507D01*
X0980847Y0882154*
X0980493Y0881624*
X0980369Y0881*
X0980493Y0880376*
X0980847Y0879846*
X0981376Y0879493*
X0982Y0879369*
X0982624Y0879493*
X0983154Y0879846*
X0983507Y0880376*
X0983631Y0881*
X0983507Y0881624*
X0983154Y0882154*
X0982624Y0882507*
X0982Y0882631*
G37*
G36*
X0953D02*
X0952376Y0882507D01*
X0951847Y0882154*
X0951493Y0881624*
X0951369Y0881*
X0951493Y0880376*
X0951847Y0879846*
X0952376Y0879493*
X0953Y0879369*
X0953624Y0879493*
X0954154Y0879846*
X0954507Y0880376*
X0954631Y0881*
X0954507Y0881624*
X0954154Y0882154*
X0953624Y0882507*
X0953Y0882631*
G37*
G36*
X0921D02*
X0920376Y0882507D01*
X0919847Y0882154*
X0919493Y0881624*
X0919369Y0881*
X0919493Y0880376*
X0919847Y0879846*
X0920376Y0879493*
X0921Y0879369*
X0921624Y0879493*
X0922153Y0879846*
X0922507Y0880376*
X0922631Y0881*
X0922507Y0881624*
X0922153Y0882154*
X0921624Y0882507*
X0921Y0882631*
G37*
G36*
X0871257Y0880632D02*
X0870632Y0880508D01*
X0870103Y0880154*
X086975Y0879625*
X0869625Y0879001*
X086975Y0878376*
X0870103Y0877847*
X0870632Y0877494*
X0871257Y0877369*
X0871881Y0877494*
X087241Y0877847*
X0872764Y0878376*
X0872888Y0879001*
X0872764Y0879625*
X087241Y0880154*
X0871881Y0880508*
X0871257Y0880632*
G37*
G36*
X1215921Y0888149D02*
X1206079D01*
X1204585Y0887952*
X1203193Y0887376*
X1201998Y0886458*
X1201081Y0885263*
X1200505Y0883871*
X1200308Y0882378*
X1200505Y0880884*
X1201081Y0879493*
X1201998Y0878298*
X1203193Y087738*
X1204585Y0876804*
X1206079Y0876607*
X1215921*
X1217415Y0876804*
X1218807Y087738*
X1220002Y0878298*
X1220919Y0879493*
X1221495Y0880884*
X1221692Y0882378*
X1221495Y0883871*
X1220919Y0885263*
X1220002Y0886458*
X1218807Y0887376*
X1217415Y0887952*
X1215921Y0888149*
G37*
G36*
X10245Y0879631D02*
X1023876Y0879507D01*
X1023347Y0879154*
X1022993Y0878624*
X1022869Y0878*
X1022993Y0877376*
X1023347Y0876847*
X1023876Y0876493*
X10245Y0876369*
X1025124Y0876493*
X1025653Y0876847*
X1026007Y0877376*
X1026131Y0878*
X1026007Y0878624*
X1025653Y0879154*
X1025124Y0879507*
X10245Y0879631*
G37*
G36*
X1289035Y0886771D02*
X1287542Y0886574D01*
X128615Y0885997*
X1284955Y0885081*
X1284038Y0883885*
X1283461Y0882493*
X1283265Y0881*
X1283461Y0879506*
X1284038Y0878115*
X1284955Y0876919*
X128615Y0876003*
X1287542Y0875426*
X1289035Y0875229*
X1290529Y0875426*
X1291921Y0876003*
X1293116Y0876919*
X1294033Y0878115*
X1294609Y0879506*
X1294806Y0881*
X1294609Y0882493*
X1294033Y0883885*
X1293116Y0885081*
X1291921Y0885997*
X1290529Y0886574*
X1289035Y0886771*
G37*
G36*
X1255965D02*
X1254471Y0886574D01*
X1253079Y0885997*
X1251884Y0885081*
X1250967Y0883885*
X1250391Y0882493*
X1250194Y0881*
X1250391Y0879506*
X1250967Y0878115*
X1251884Y0876919*
X1253079Y0876003*
X1254471Y0875426*
X1255965Y0875229*
X1257458Y0875426*
X125885Y0876003*
X1260045Y0876919*
X1260962Y0878115*
X1261539Y0879506*
X1261735Y0881*
X1261539Y0882493*
X1260962Y0883885*
X1260045Y0885081*
X125885Y0885997*
X1257458Y0886574*
X1255965Y0886771*
G37*
G36*
X0969Y0877131D02*
X0968376Y0877007D01*
X0967846Y0876653*
X0967493Y0876124*
X0967369Y08755*
X0967493Y0874876*
X0967846Y0874347*
X0968376Y0873993*
X0969Y0873869*
X0969624Y0873993*
X0970154Y0874347*
X0970507Y0874876*
X0970631Y08755*
X0970507Y0876124*
X0970154Y0876653*
X0969624Y0877007*
X0969Y0877131*
G37*
G36*
X0898354D02*
X089773Y0877007D01*
X0897201Y0876653*
X0896847Y0876124*
X0896723Y08755*
X0896847Y0874876*
X0897201Y0874347*
X089773Y0873993*
X0898354Y0873869*
X0898979Y0873993*
X0899508Y0874347*
X0899862Y0874876*
X0899986Y08755*
X0899862Y0876124*
X0899508Y0876653*
X0898979Y0877007*
X0898354Y0877131*
G37*
G36*
X12285Y0872131D02*
X1227876Y0872007D01*
X1227347Y0871653*
X1226993Y0871124*
X1226869Y08705*
X1226993Y0869876*
X1227347Y0869347*
X1227876Y0868993*
X12285Y0868869*
X1229124Y0868993*
X1229653Y0869347*
X1230007Y0869876*
X1230131Y08705*
X1230007Y0871124*
X1229653Y0871653*
X1229124Y0872007*
X12285Y0872131*
G37*
G36*
X0784D02*
X0783376Y0872007D01*
X0782846Y0871653*
X0782493Y0871124*
X0782369Y08705*
X0782493Y0869876*
X0782846Y0869347*
X0783376Y0868993*
X0784Y0868869*
X0784624Y0868993*
X0785153Y0869347*
X0785507Y0869876*
X0785631Y08705*
X0785507Y0871124*
X0785153Y0871653*
X0784624Y0872007*
X0784Y0872131*
G37*
G36*
X1004Y0868531D02*
X1003376Y0868407D01*
X1002847Y0868054*
X1002493Y0867524*
X1002369Y08669*
X1002493Y0866276*
X1002847Y0865746*
X1003376Y0865393*
X1004Y0865269*
X1004624Y0865393*
X1005153Y0865746*
X1005507Y0866276*
X1005631Y08669*
X1005507Y0867524*
X1005153Y0868054*
X1004624Y0868407*
X1004Y0868531*
G37*
G36*
X0867Y0868131D02*
X0866376Y0868007D01*
X0865847Y0867653*
X0865493Y0867124*
X0865369Y08665*
X0865493Y0865876*
X0865847Y0865347*
X0866376Y0864993*
X0867Y0864869*
X0867624Y0864993*
X0868153Y0865347*
X0868507Y0865876*
X0868631Y08665*
X0868507Y0867124*
X0868153Y0867653*
X0867624Y0868007*
X0867Y0868131*
G37*
G36*
X07745D02*
X0773876Y0868007D01*
X0773347Y0867653*
X0772993Y0867124*
X0772869Y08665*
X0772993Y0865876*
X0773347Y0865347*
X0773876Y0864993*
X07745Y0864869*
X0775124Y0864993*
X0775654Y0865347*
X0776007Y0865876*
X0776131Y08665*
X0776007Y0867124*
X0775654Y0867653*
X0775124Y0868007*
X07745Y0868131*
G37*
G36*
X09415Y0865631D02*
X0940876Y0865507D01*
X0940347Y0865154*
X0939993Y0864624*
X0939869Y0864*
X0939993Y0863376*
X0940347Y0862846*
X0940876Y0862493*
X09415Y0862369*
X0942124Y0862493*
X0942653Y0862846*
X0943007Y0863376*
X0943131Y0864*
X0943007Y0864624*
X0942653Y0865154*
X0942124Y0865507*
X09415Y0865631*
G37*
G36*
X09265Y0862631D02*
X0925876Y0862507D01*
X0925346Y0862154*
X0924993Y0861624*
X0924869Y0861*
X0924873Y0860976*
X0924402Y0860781*
X0924154Y0861154*
X0923624Y0861507*
X0923Y0861631*
X0922376Y0861507*
X0921846Y0861154*
X0921493Y0860624*
X0921369Y086*
X0921493Y0859376*
X0921846Y0858846*
X0922376Y0858493*
X0923Y0858369*
X0923624Y0858493*
X0924154Y0858846*
X0924507Y0859376*
X0924631Y086*
X0924627Y0860024*
X0925098Y0860219*
X0925346Y0859846*
X0925876Y0859493*
X09265Y0859369*
X0927124Y0859493*
X0927654Y0859846*
X0928007Y0860376*
X0928131Y0861*
X0928007Y0861624*
X0927654Y0862154*
X0927124Y0862507*
X09265Y0862631*
G37*
G36*
X0879Y0863631D02*
X0878376Y0863507D01*
X0877847Y0863153*
X0877493Y0862624*
X0877369Y0862*
X0877493Y0861376*
X0877847Y0860847*
X0878376Y0860493*
X0879Y0860369*
X0879624Y0860493*
X0880153Y0860847*
X0880507Y0861376*
X0880631Y0862*
X0880507Y0862624*
X0880153Y0863153*
X0879624Y0863507*
X0879Y0863631*
G37*
G36*
X0813Y0863131D02*
X0812376Y0863007D01*
X0811847Y0862654*
X0811493Y0862124*
X0811369Y08615*
X0811493Y0860876*
X0811847Y0860347*
X0812376Y0859993*
X0813Y0859869*
X0813624Y0859993*
X0814153Y0860347*
X0814507Y0860876*
X0814631Y08615*
X0814507Y0862124*
X0814153Y0862654*
X0813624Y0863007*
X0813Y0863131*
G37*
G36*
X1066Y0862631D02*
X1065376Y0862507D01*
X1064847Y0862154*
X1064493Y0861624*
X1064369Y0861*
X1064493Y0860376*
X1064847Y0859846*
X1065376Y0859493*
X1066Y0859369*
X1066624Y0859493*
X1067153Y0859846*
X1067507Y0860376*
X1067631Y0861*
X1067507Y0861624*
X1067153Y0862154*
X1066624Y0862507*
X1066Y0862631*
G37*
G36*
X07875Y0862131D02*
X0786876Y0862007D01*
X0786346Y0861654*
X0785993Y0861124*
X0785869Y08605*
X0785993Y0859876*
X0786346Y0859346*
X0786876Y0858993*
X07875Y0858869*
X0788124Y0858993*
X0788654Y0859346*
X0789007Y0859876*
X0789131Y08605*
X0789007Y0861124*
X0788654Y0861654*
X0788124Y0862007*
X07875Y0862131*
G37*
G36*
X0754Y0864131D02*
X0753376Y0864007D01*
X0752846Y0863653*
X0752493Y0863124*
X0752369Y08625*
X0752493Y0861876*
X0752846Y0861347*
X0753376Y0860993*
X0754Y0860869*
X0754624Y0860993*
X0754649Y0861009*
X0755009Y0860649*
X0754993Y0860624*
X0754869Y086*
X0754993Y0859376*
X0755346Y0858846*
X0755876Y0858493*
X07565Y0858369*
X0757124Y0858493*
X0757654Y0858846*
X0758007Y0859376*
X0758131Y086*
X0758007Y0860624*
X0757654Y0861154*
X0757124Y0861507*
X07565Y0861631*
X0755876Y0861507*
X0755851Y0861491*
X0755491Y0861851*
X0755507Y0861876*
X0755631Y08625*
X0755507Y0863124*
X0755154Y0863653*
X0754624Y0864007*
X0754Y0864131*
G37*
G36*
X084075Y0863026D02*
X0839854Y0862848D01*
X0839095Y086234*
X0838587Y0861581*
X0838409Y0860685*
X0838587Y0859789*
X0839095Y085903*
X0839854Y0858522*
X084075Y0858344*
X0841646Y0858522*
X0842405Y085903*
X0842913Y0859789*
X0843091Y0860685*
X0842913Y0861581*
X0842405Y086234*
X0841646Y0862848*
X084075Y0863026*
G37*
G36*
X08765Y0858631D02*
X0875876Y0858507D01*
X0875346Y0858154*
X0874993Y0857624*
X0874869Y0857*
X0874993Y0856376*
X0875346Y0855847*
X0875876Y0855493*
X08765Y0855369*
X0877124Y0855493*
X0877654Y0855847*
X0878007Y0856376*
X0878131Y0857*
X0878007Y0857624*
X0877654Y0858154*
X0877124Y0858507*
X08765Y0858631*
G37*
G36*
X07431Y0857731D02*
X0742476Y0857607D01*
X0741947Y0857253*
X0741593Y0856724*
X0741469Y08561*
X0741593Y0855476*
X0741947Y0854947*
X0742476Y0854593*
X07431Y0854469*
X0743724Y0854593*
X0744253Y0854947*
X0744607Y0855476*
X0744731Y08561*
X0744607Y0856724*
X0744253Y0857253*
X0743724Y0857607*
X07431Y0857731*
G37*
G36*
X11985Y0857231D02*
X1197876Y0857107D01*
X1197346Y0856754*
X1196993Y0856224*
X1196869Y08556*
X1196993Y0854976*
X1197346Y0854447*
X1197876Y0854093*
X11985Y0853969*
X1199124Y0854093*
X1199654Y0854447*
X1200007Y0854976*
X1200131Y08556*
X1200007Y0856224*
X1199654Y0856754*
X1199124Y0857107*
X11985Y0857231*
G37*
G36*
X12725Y0865117D02*
X1271006Y0864921D01*
X1269615Y0864344*
X1268419Y0863427*
X1267502Y0862232*
X1266926Y086084*
X1266729Y0859346*
X1266926Y0857853*
X1267502Y0856461*
X1268419Y0855266*
X1269615Y0854349*
X1271006Y0853773*
X12725Y0853576*
X1273993Y0853773*
X1275385Y0854349*
X1276581Y0855266*
X1277497Y0856461*
X1278074Y0857853*
X1278271Y0859346*
X1278074Y086084*
X1277497Y0862232*
X1276581Y0863427*
X1275385Y0864344*
X1273993Y0864921*
X12725Y0865117*
G37*
G36*
X08425Y0856631D02*
X0841876Y0856507D01*
X0841346Y0856153*
X0840993Y0855624*
X0840869Y0855*
X0840993Y0854376*
X0841346Y0853846*
X0841876Y0853493*
X08425Y0853369*
X0843124Y0853493*
X0843653Y0853846*
X0844007Y0854376*
X0844131Y0855*
X0844007Y0855624*
X0843653Y0856153*
X0843124Y0856507*
X08425Y0856631*
G37*
G36*
X08245Y0855631D02*
X0823876Y0855507D01*
X0823347Y0855153*
X0822993Y0854624*
X0822869Y0854*
X0822993Y0853376*
X0823265Y0852969*
X082298Y0852536*
X08225Y0852631*
X0821876Y0852507*
X0821346Y0852153*
X0820993Y0851624*
X0820869Y0851*
X0820993Y0850376*
X0821346Y0849846*
X0821876Y0849493*
X08225Y0849369*
X0823124Y0849493*
X0823654Y0849846*
X0824007Y0850376*
X0824131Y0851*
X0824007Y0851624*
X0823735Y0852031*
X082402Y0852464*
X08245Y0852369*
X0825124Y0852493*
X0825653Y0852847*
X0826007Y0853376*
X0826131Y0854*
X0826007Y0854624*
X0825653Y0855153*
X0825124Y0855507*
X08245Y0855631*
G37*
G36*
X11265Y0853131D02*
X1125876Y0853007D01*
X1125346Y0852654*
X1124993Y0852124*
X1124869Y08515*
X1124993Y0850876*
X1125346Y0850346*
X1125876Y0849993*
X11265Y0849869*
X1127124Y0849993*
X1127654Y0850346*
X1128007Y0850876*
X1128131Y08515*
X1128007Y0852124*
X1127654Y0852654*
X1127124Y0853007*
X11265Y0853131*
G37*
G36*
X09613Y0850631D02*
X0960676Y0850507D01*
X0960147Y0850154*
X0959793Y0849624*
X0959669Y0849*
X0959793Y0848376*
X0960147Y0847847*
X0960676Y0847493*
X09613Y0847369*
X0961924Y0847493*
X0962453Y0847847*
X0962807Y0848376*
X0962931Y0849*
X0962807Y0849624*
X0962453Y0850154*
X0961924Y0850507*
X09613Y0850631*
G37*
G36*
X0857D02*
X0856376Y0850507D01*
X0855847Y0850154*
X0855493Y0849624*
X0855369Y0849*
X0855493Y0848376*
X0855847Y0847847*
X0856376Y0847493*
X0857Y0847369*
X0857624Y0847493*
X0858154Y0847847*
X0858507Y0848376*
X0858631Y0849*
X0858507Y0849624*
X0858154Y0850154*
X0857624Y0850507*
X0857Y0850631*
G37*
G36*
X0952Y0850131D02*
X0951376Y0850007D01*
X0950846Y0849654*
X0950493Y0849124*
X0950369Y08485*
X0950493Y0847876*
X0950846Y0847346*
X0951376Y0846993*
X0952Y0846869*
X0952624Y0846993*
X0953154Y0847346*
X0953507Y0847876*
X0953631Y08485*
X0953507Y0849124*
X0953154Y0849654*
X0952624Y0850007*
X0952Y0850131*
G37*
G36*
X0838D02*
X0837376Y0850007D01*
X0836847Y0849654*
X0836493Y0849124*
X0836369Y08485*
X0836493Y0847876*
X0836847Y0847346*
X0837376Y0846993*
X0838Y0846869*
X0838624Y0846993*
X0839153Y0847346*
X0839507Y0847876*
X0839631Y08485*
X0839507Y0849124*
X0839153Y0849654*
X0838624Y0850007*
X0838Y0850131*
G37*
G36*
X125Y0847631D02*
X1249376Y0847507D01*
X1248847Y0847153*
X1248493Y0846624*
X1248369Y0846*
X1248493Y0845376*
X1248847Y0844847*
X1249376Y0844493*
X125Y0844369*
X1250624Y0844493*
X1251153Y0844847*
X1251507Y0845376*
X1251631Y0846*
X1251507Y0846624*
X1251153Y0847153*
X1250624Y0847507*
X125Y0847631*
G37*
G36*
X09427Y0847731D02*
X0942076Y0847607D01*
X0941547Y0847254*
X0941193Y0846724*
X0941069Y08461*
X0941193Y0845476*
X0941547Y0844946*
X0942076Y0844593*
X09427Y0844469*
X0943324Y0844593*
X0943853Y0844946*
X0944039Y0845224*
X0944077Y0845237*
X0944617Y0845189*
X0944847Y0844847*
X0945376Y0844493*
X0946Y0844369*
X0946624Y0844493*
X0947153Y0844847*
X0947507Y0845376*
X0947631Y0846*
X0947507Y0846624*
X0947153Y0847153*
X0946624Y0847507*
X0946Y0847631*
X0945376Y0847507*
X0944847Y0847153*
X0944661Y0846876*
X0944623Y0846863*
X0944083Y084691*
X0943853Y0847254*
X0943324Y0847607*
X09427Y0847731*
G37*
G36*
X09349Y0846831D02*
X0934276Y0846707D01*
X0933747Y0846354*
X0933393Y0845824*
X0933269Y08452*
X0933393Y0844576*
X0933747Y0844046*
X0934276Y0843693*
X09349Y0843569*
X0935524Y0843693*
X0936053Y0844046*
X0936407Y0844576*
X0936435Y0844716*
X0936945*
X0936993Y0844476*
X0937346Y0843946*
X0937876Y0843593*
X09385Y0843469*
X0939124Y0843593*
X0939653Y0843946*
X0940007Y0844476*
X0940131Y08451*
X0940007Y0845724*
X0939653Y0846253*
X0939124Y0846607*
X09385Y0846731*
X0937876Y0846607*
X0937346Y0846253*
X0936993Y0845724*
X0936965Y0845584*
X0936455*
X0936407Y0845824*
X0936053Y0846354*
X0935524Y0846707*
X09349Y0846831*
G37*
G36*
X084075Y0847278D02*
X0839854Y08471D01*
X0839095Y0846592*
X0838587Y0845833*
X0838409Y0844937*
X0838587Y0844041*
X0839095Y0843282*
X0839854Y0842774*
X084075Y0842596*
X0841646Y0842774*
X0842405Y0843282*
X0842913Y0844041*
X0843091Y0844937*
X0842913Y0845833*
X0842405Y0846592*
X0841646Y08471*
X084075Y0847278*
G37*
G36*
X1247Y0844631D02*
X1246376Y0844507D01*
X1245846Y0844153*
X1245493Y0843624*
X1245369Y0843*
X1245493Y0842376*
X1245846Y0841846*
X1246376Y0841493*
X1247Y0841369*
X1247624Y0841493*
X1248153Y0841846*
X1248507Y0842376*
X1248631Y0843*
X1248507Y0843624*
X1248153Y0844153*
X1247624Y0844507*
X1247Y0844631*
G37*
G36*
X08625Y0842631D02*
X0861876Y0842507D01*
X0861347Y0842153*
X0860993Y0841624*
X0860869Y0841*
X0860993Y0840376*
X0861347Y0839847*
X0861876Y0839493*
X08625Y0839369*
X0863124Y0839493*
X0863653Y0839847*
X0864007Y0840376*
X0864131Y0841*
X0864007Y0841624*
X0863653Y0842153*
X0863124Y0842507*
X08625Y0842631*
G37*
G36*
X1243773Y0841631D02*
X1243149Y0841507D01*
X124262Y0841154*
X1242266Y0840624*
X1242142Y084*
X1242266Y0839376*
X124262Y0838846*
X1243149Y0838493*
X1243773Y0838369*
X1244398Y0838493*
X1244927Y0838846*
X1245281Y0839376*
X1245405Y084*
X1245281Y0840624*
X1244927Y0841154*
X1244398Y0841507*
X1243773Y0841631*
G37*
G36*
X124Y0839131D02*
X1239376Y0839007D01*
X1238846Y0838653*
X1238493Y0838124*
X1238369Y08375*
X1238493Y0836876*
X1238846Y0836347*
X1239376Y0835993*
X124Y0835869*
X1240624Y0835993*
X1241154Y0836347*
X1241507Y0836876*
X1241631Y08375*
X1241507Y0838124*
X1241154Y0838653*
X1240624Y0839007*
X124Y0839131*
G37*
G36*
X09293Y0836431D02*
X0928676Y0836307D01*
X0928146Y0835954*
X0927793Y0835424*
X0927669Y08348*
X0927793Y0834176*
X0928146Y0833646*
X0928676Y0833293*
X09293Y0833169*
X0929924Y0833293*
X0930453Y0833646*
X0930807Y0834176*
X0930931Y08348*
X0930807Y0835424*
X0930453Y0835954*
X0929924Y0836307*
X09293Y0836431*
G37*
G36*
X1234491Y0835139D02*
X1233866Y0835015D01*
X1233337Y0834661*
X1232983Y0834132*
X1232859Y0833508*
X1232983Y0832883*
X1233337Y0832354*
X1233866Y0832*
X1234491Y0831876*
X1235115Y0832*
X1235644Y0832354*
X1235998Y0832883*
X1236122Y0833508*
X1235998Y0834132*
X1235644Y0834661*
X1235115Y0835015*
X1234491Y0835139*
G37*
G36*
X08717Y0834531D02*
X0871076Y0834407D01*
X0870547Y0834054*
X0870193Y0833524*
X0870069Y08329*
X0870193Y0832276*
X0870547Y0831746*
X0871076Y0831393*
X08717Y0831269*
X0872324Y0831393*
X0872853Y0831746*
X0873207Y0832276*
X0873331Y08329*
X0873207Y0833524*
X0872853Y0834054*
X0872324Y0834407*
X08717Y0834531*
G37*
G36*
X0953302Y0833929D02*
X0952678Y0833805D01*
X0952149Y0833451*
X0951795Y0832922*
X0951671Y0832298*
X0951795Y0831674*
X0952149Y0831144*
X0952678Y0830791*
X0953302Y0830666*
X0953926Y0830791*
X0954456Y0831144*
X0954809Y0831674*
X0954934Y0832298*
X0954809Y0832922*
X0954456Y0833451*
X0953926Y0833805*
X0953302Y0833929*
G37*
G36*
X09482Y0831731D02*
X0947576Y0831607D01*
X0947046Y0831254*
X0946693Y0830724*
X0946569Y08301*
X0946693Y0829476*
X0947046Y0828946*
X0947576Y0828593*
X09482Y0828469*
X0948824Y0828593*
X0949354Y0828946*
X0949707Y0829476*
X0949831Y08301*
X0949707Y0830724*
X0949354Y0831254*
X0948824Y0831607*
X09482Y0831731*
G37*
G36*
X09644Y0831331D02*
X0963776Y0831207D01*
X0963247Y0830853*
X0962893Y0830324*
X0962769Y08297*
X0962893Y0829076*
X0963247Y0828547*
X0963776Y0828193*
X09644Y0828069*
X0965024Y0828193*
X0965553Y0828547*
X0965907Y0829076*
X0966031Y08297*
X0965907Y0830324*
X0965553Y0830853*
X0965024Y0831207*
X09644Y0831331*
G37*
G36*
X09243D02*
X0923676Y0831207D01*
X0923147Y0830853*
X0922793Y0830324*
X0922669Y08297*
X0922793Y0829076*
X0923147Y0828547*
X0923676Y0828193*
X09243Y0828069*
X0924924Y0828193*
X0925453Y0828547*
X0925807Y0829076*
X0925931Y08297*
X0925807Y0830324*
X0925453Y0830853*
X0924924Y0831207*
X09243Y0831331*
G37*
G36*
X12435Y0831131D02*
X1242876Y0831007D01*
X1242346Y0830653*
X1241993Y0830124*
X1241869Y08295*
X1241993Y0828876*
X1242346Y0828347*
X1242876Y0827993*
X12435Y0827869*
X1244124Y0827993*
X1244654Y0828347*
X1245007Y0828876*
X1245131Y08295*
X1245007Y0830124*
X1244654Y0830653*
X1244124Y0831007*
X12435Y0831131*
G37*
G36*
X08581Y0830831D02*
X0857476Y0830707D01*
X0856946Y0830354*
X0856593Y0829824*
X0856469Y08292*
X0856593Y0828576*
X0856946Y0828047*
X0857476Y0827693*
X08581Y0827569*
X0858724Y0827693*
X0859254Y0828047*
X0859607Y0828576*
X0859731Y08292*
X0859607Y0829824*
X0859254Y0830354*
X0858724Y0830707*
X08581Y0830831*
G37*
G36*
X09365Y0829331D02*
X0935876Y0829207D01*
X0935347Y0828854*
X0934993Y0828324*
X0934869Y08277*
X0934993Y0827076*
X0935347Y0826546*
X0935876Y0826193*
X09365Y0826069*
X0937124Y0826193*
X0937654Y0826546*
X0938007Y0827076*
X0938131Y08277*
X0938007Y0828324*
X0937654Y0828854*
X0937124Y0829207*
X09365Y0829331*
G37*
G36*
X12325Y0828631D02*
X1231876Y0828507D01*
X1231347Y0828154*
X1230993Y0827624*
X1230869Y0827*
X1230993Y0826376*
X1231347Y0825846*
X1231876Y0825493*
X12325Y0825369*
X1233124Y0825493*
X1233654Y0825846*
X1234007Y0826376*
X1234131Y0827*
X1234007Y0827624*
X1233654Y0828154*
X1233124Y0828507*
X12325Y0828631*
G37*
G36*
X09735Y0828131D02*
X0972876Y0828007D01*
X0972346Y0827654*
X0971993Y0827124*
X0971869Y08265*
X0971993Y0825876*
X0972346Y0825346*
X0972876Y0824993*
X09735Y0824869*
X0974124Y0824993*
X0974654Y0825346*
X0975007Y0825876*
X0975131Y08265*
X0975007Y0827124*
X0974654Y0827654*
X0974124Y0828007*
X09735Y0828131*
G37*
G36*
X0825D02*
X0824376Y0828007D01*
X0823847Y0827654*
X0823493Y0827124*
X0823369Y08265*
X0823493Y0825876*
X0823847Y0825346*
X0824376Y0824993*
X0825Y0824869*
X0825624Y0824993*
X0826153Y0825346*
X0826507Y0825876*
X0826631Y08265*
X0826507Y0827124*
X0826153Y0827654*
X0825624Y0828007*
X0825Y0828131*
G37*
G36*
X09221Y0825531D02*
X0921476Y0825407D01*
X0920947Y0825054*
X0920593Y0824524*
X0920469Y08239*
X0920593Y0823276*
X0920947Y0822746*
X0921476Y0822393*
X09221Y0822269*
X0922724Y0822393*
X0923254Y0822746*
X0923607Y0823276*
X0923731Y08239*
X0923607Y0824524*
X0923254Y0825054*
X0922724Y0825407*
X09221Y0825531*
G37*
G36*
X084125Y0826704D02*
X0840354Y0826526D01*
X0839595Y0826018*
X0839087Y0825259*
X0838909Y0824363*
X0839087Y0823467*
X0839595Y0822708*
X0840354Y08222*
X084125Y0822022*
X0842146Y08222*
X0842905Y0822708*
X0843413Y0823467*
X0843591Y0824363*
X0843413Y0825259*
X0842905Y0826018*
X0842146Y0826526*
X084125Y0826704*
G37*
G36*
X1227257Y0824631D02*
X1226633Y0824507D01*
X1226104Y0824154*
X122575Y0823624*
X1225626Y0823*
X122575Y0822376*
X1226104Y0821846*
X1226633Y0821493*
X1227257Y0821369*
X1227882Y0821493*
X1228411Y0821846*
X1228765Y0822376*
X1228889Y0823*
X1228765Y0823624*
X1228411Y0824154*
X1227882Y0824507*
X1227257Y0824631*
G37*
G36*
X09797Y0825531D02*
X0979076Y0825407D01*
X0978547Y0825054*
X0978193Y0824524*
X0978069Y08239*
X0978193Y0823276*
X0978547Y0822746*
X0978772Y0822596*
X0978666Y0822065*
X0978376Y0822007*
X0977847Y0821653*
X0977493Y0821124*
X0977369Y08205*
X0977493Y0819876*
X0977847Y0819347*
X0978376Y0818993*
X0979Y0818869*
X0979624Y0818993*
X0980153Y0819347*
X0980507Y0819876*
X0980631Y08205*
X0980507Y0821124*
X0980153Y0821653*
X0979928Y0821804*
X0980034Y0822335*
X0980324Y0822393*
X0980853Y0822746*
X0981207Y0823276*
X0981331Y08239*
X0981207Y0824524*
X0980853Y0825054*
X0980324Y0825407*
X09797Y0825531*
G37*
G36*
X08582Y0822031D02*
X0857576Y0821907D01*
X0857047Y0821554*
X0856693Y0821024*
X0856569Y08204*
X0856693Y0819776*
X0857047Y0819246*
X0857576Y0818893*
X08582Y0818769*
X0858824Y0818893*
X0859354Y0819246*
X0859707Y0819776*
X0859831Y08204*
X0859707Y0821024*
X0859354Y0821554*
X0858824Y0821907*
X08582Y0822031*
G37*
G36*
X08196D02*
X0818976Y0821907D01*
X0818447Y0821554*
X0818093Y0821024*
X0817969Y08204*
X0818093Y0819776*
X0818447Y0819246*
X0818976Y0818893*
X08196Y0818769*
X0820224Y0818893*
X0820753Y0819246*
X0821107Y0819776*
X0821231Y08204*
X0821107Y0821024*
X0820753Y0821554*
X0820224Y0821907*
X08196Y0822031*
G37*
G36*
X1229957Y0821931D02*
X1229333Y0821807D01*
X1228804Y0821453*
X122845Y0820924*
X1228326Y08203*
X122845Y0819676*
X1228804Y0819147*
X1229333Y0818793*
X1229957Y0818669*
X1230582Y0818793*
X1231111Y0819147*
X1231464Y0819676*
X1231589Y08203*
X1231464Y0820924*
X1231111Y0821453*
X1230582Y0821807*
X1229957Y0821931*
G37*
G36*
X0841Y0821431D02*
X0840376Y0821307D01*
X0839847Y0820953*
X0839493Y0820424*
X0839369Y08198*
X0839493Y0819176*
X0839847Y0818647*
X0840376Y0818293*
X0841Y0818169*
X0841624Y0818293*
X0842153Y0818647*
X0842507Y0819176*
X0842631Y08198*
X0842507Y0820424*
X0842153Y0820953*
X0841624Y0821307*
X0841Y0821431*
G37*
G36*
X1243Y0821131D02*
X1242376Y0821007D01*
X1241846Y0820654*
X1241493Y0820124*
X1241369Y08195*
X1241493Y0818876*
X1241846Y0818347*
X1242376Y0817993*
X1243Y0817869*
X1243624Y0817993*
X1244153Y0818347*
X1244507Y0818876*
X1244631Y08195*
X1244507Y0820124*
X1244153Y0820654*
X1243624Y0821007*
X1243Y0821131*
G37*
G36*
X08716Y0818031D02*
X0870976Y0817907D01*
X0870446Y0817554*
X0870093Y0817024*
X0869969Y08164*
X0870093Y0815776*
X0870446Y0815246*
X0870976Y0814893*
X08716Y0814769*
X0872224Y0814893*
X0872754Y0815246*
X0873107Y0815776*
X0873231Y08164*
X0873107Y0817024*
X0872754Y0817554*
X0872224Y0817907*
X08716Y0818031*
G37*
G36*
X09048Y0817531D02*
X0904176Y0817407D01*
X0903646Y0817054*
X0903293Y0816524*
X0903169Y08159*
X0903293Y0815276*
X0903646Y0814746*
X0904176Y0814393*
X09048Y0814269*
X0905424Y0814393*
X0905954Y0814746*
X0906307Y0815276*
X0906431Y08159*
X0906307Y0816524*
X0905954Y0817054*
X0905424Y0817407*
X09048Y0817531*
G37*
G36*
X1233Y0817131D02*
X1232376Y0817007D01*
X1231847Y0816654*
X1231493Y0816124*
X1231369Y08155*
X1231493Y0814876*
X1231847Y0814347*
X1232376Y0813993*
X1233Y0813869*
X1233624Y0813993*
X1234153Y0814347*
X1234507Y0814876*
X1234631Y08155*
X1234507Y0816124*
X1234153Y0816654*
X1233624Y0817007*
X1233Y0817131*
G37*
G36*
X0982Y0819631D02*
X0981376Y0819507D01*
X0980847Y0819153*
X0980493Y0818624*
X0980369Y0818*
X0980493Y0817376*
X0980847Y0816846*
X0981376Y0816493*
X0982Y0816369*
X0982624Y0816493*
X0982649Y0816509*
X0983009Y0816149*
X0982993Y0816124*
X0982869Y08155*
X0982993Y0814876*
X0983346Y0814347*
X0983876Y0813993*
X09845Y0813869*
X0985124Y0813993*
X0985653Y0814347*
X0986007Y0814876*
X0986131Y08155*
X0986007Y0816124*
X0985653Y0816654*
X0985124Y0817007*
X09845Y0817131*
X0983876Y0817007*
X0983851Y0816991*
X0983491Y0817351*
X0983507Y0817376*
X0983631Y0818*
X0983507Y0818624*
X0983154Y0819153*
X0982624Y0819507*
X0982Y0819631*
G37*
G36*
X0745Y0816731D02*
X0744376Y0816607D01*
X0743847Y0816253*
X0743493Y0815724*
X0743369Y08151*
X0743493Y0814476*
X0743847Y0813947*
X0744376Y0813593*
X0745Y0813469*
X0745624Y0813593*
X0746153Y0813947*
X0746507Y0814476*
X0746631Y08151*
X0746507Y0815724*
X0746153Y0816253*
X0745624Y0816607*
X0745Y0816731*
G37*
G36*
X09592Y0815831D02*
X0958576Y0815707D01*
X0958047Y0815353*
X0957693Y0814824*
X0957569Y08142*
X0957693Y0813576*
X0958047Y0813046*
X0958576Y0812693*
X09592Y0812569*
X0959824Y0812693*
X0960353Y0813046*
X0960707Y0813576*
X0960831Y08142*
X0960707Y0814824*
X0960353Y0815353*
X0959824Y0815707*
X09592Y0815831*
G37*
G36*
X12295Y0814131D02*
X1228876Y0814007D01*
X1228347Y0813653*
X1227993Y0813124*
X1227869Y08125*
X1227993Y0811876*
X1228347Y0811347*
X1228876Y0810993*
X12295Y0810869*
X1230124Y0810993*
X1230653Y0811347*
X1231007Y0811876*
X1231131Y08125*
X1231007Y0813124*
X1230653Y0813653*
X1230124Y0814007*
X12295Y0814131*
G37*
G36*
X0993D02*
X0992376Y0814007D01*
X0991846Y0813653*
X0991493Y0813124*
X0991369Y08125*
X0991493Y0811876*
X0991846Y0811347*
X0992376Y0810993*
X0993Y0810869*
X0993624Y0810993*
X0994153Y0811347*
X0994507Y0811876*
X0994631Y08125*
X0994507Y0813124*
X0994153Y0813653*
X0993624Y0814007*
X0993Y0814131*
G37*
G36*
X09482Y0812331D02*
X0947576Y0812207D01*
X0947046Y0811854*
X0946693Y0811324*
X0946569Y08107*
X0946693Y0810076*
X0947046Y0809546*
X0947576Y0809193*
X09482Y0809069*
X0948824Y0809193*
X0949354Y0809546*
X0949707Y0810076*
X0949831Y08107*
X0949707Y0811324*
X0949354Y0811854*
X0948824Y0812207*
X09482Y0812331*
G37*
G36*
X08495Y0810231D02*
X0848876Y0810107D01*
X0848347Y0809754*
X0847993Y0809224*
X0847869Y08086*
X0847993Y0807976*
X0848347Y0807446*
X0848876Y0807093*
X08495Y0806969*
X0850124Y0807093*
X0850653Y0807446*
X0851007Y0807976*
X0851131Y08086*
X0851007Y0809224*
X0850653Y0809754*
X0850124Y0810107*
X08495Y0810231*
G37*
G36*
X08414Y0814331D02*
X0840776Y0814207D01*
X0840246Y0813853*
X0839893Y0813324*
X0839769Y08127*
X0839893Y0812076*
X0840246Y0811547*
X084057Y0811331*
X0840464Y08108*
X0840354Y0810778*
X0839595Y081027*
X0839087Y0809511*
X0838909Y0808615*
X0839087Y0807719*
X0839595Y080696*
X0840354Y0806452*
X084125Y0806274*
X0842146Y0806452*
X0842905Y080696*
X0843413Y0807719*
X0843591Y0808615*
X0843413Y0809511*
X0842905Y081027*
X084219Y0810748*
X0842179Y0810777*
X0842152Y0810984*
X0842161Y0811285*
X0842554Y0811547*
X0842907Y0812076*
X0843031Y08127*
X0842907Y0813324*
X0842554Y0813853*
X0842024Y0814207*
X08414Y0814331*
G37*
G36*
X09359Y0807031D02*
X0935276Y0806907D01*
X0934746Y0806553*
X0934393Y0806024*
X0934269Y08054*
X0934393Y0804776*
X0934746Y0804247*
X0935276Y0803893*
X09359Y0803769*
X0936524Y0803893*
X0937053Y0804247*
X0937407Y0804776*
X0937531Y08054*
X0937407Y0806024*
X0937053Y0806553*
X0936524Y0806907*
X09359Y0807031*
G37*
G36*
X08975Y0806631D02*
X0896876Y0806507D01*
X0896346Y0806153*
X0895993Y0805624*
X0895869Y0805*
X0895993Y0804376*
X0896346Y0803846*
X0896876Y0803493*
X08975Y0803369*
X0898124Y0803493*
X0898654Y0803846*
X0899007Y0804376*
X0899131Y0805*
X0899007Y0805624*
X0898654Y0806153*
X0898124Y0806507*
X08975Y0806631*
G37*
G36*
X09335Y0801631D02*
X0932876Y0801507D01*
X0932347Y0801153*
X0931993Y0800624*
X0931869Y08*
X0931993Y0799376*
X0932347Y0798846*
X0932876Y0798493*
X09335Y0798369*
X0934124Y0798493*
X0934653Y0798846*
X0935007Y0799376*
X0935131Y08*
X0935007Y0800624*
X0934653Y0801153*
X0934124Y0801507*
X09335Y0801631*
G37*
G36*
X0907Y0800131D02*
X0906376Y0800007D01*
X0905847Y0799653*
X0905493Y0799124*
X0905369Y07985*
X0905493Y0797876*
X0905847Y0797346*
X0906376Y0796993*
X0907Y0796869*
X0907624Y0796993*
X0908154Y0797346*
X0908507Y0797876*
X0908631Y07985*
X0908507Y0799124*
X0908154Y0799653*
X0907624Y0800007*
X0907Y0800131*
G37*
G36*
X09188Y0799031D02*
X0918176Y0798907D01*
X0917647Y0798554*
X0917293Y0798024*
X0917169Y07974*
X0917293Y0796776*
X0917647Y0796246*
X0918176Y0795893*
X09188Y0795769*
X0919424Y0795893*
X0919954Y0796246*
X0920307Y0796776*
X0920431Y07974*
X0920307Y0798024*
X0919954Y0798554*
X0919424Y0798907*
X09188Y0799031*
G37*
G36*
X0957Y0796331D02*
X0956376Y0796207D01*
X0955847Y0795854*
X0955493Y0795324*
X0955369Y07947*
X0955493Y0794076*
X0955847Y0793546*
X0956376Y0793193*
X0957Y0793069*
X0957624Y0793193*
X0958154Y0793546*
X0958507Y0794076*
X0958631Y07947*
X0958507Y0795324*
X0958154Y0795854*
X0957624Y0796207*
X0957Y0796331*
G37*
G36*
X09592Y0791231D02*
X0958576Y0791107D01*
X0958047Y0790754*
X0957693Y0790224*
X0957569Y07896*
X0957693Y0788976*
X0958047Y0788447*
X0958576Y0788093*
X09592Y0787969*
X0959824Y0788093*
X0960353Y0788447*
X0960707Y0788976*
X0960831Y07896*
X0960707Y0790224*
X0960353Y0790754*
X0959824Y0791107*
X09592Y0791231*
G37*
G36*
X1049382Y0781013D02*
X1048758Y0780889D01*
X1048228Y0780535*
X1047875Y0780006*
X104775Y0779382*
X1047875Y0778758*
X1048228Y0778228*
X1048758Y0777875*
X1049382Y077775*
X1050006Y0777875*
X1050535Y0778228*
X1050889Y0778758*
X1051013Y0779382*
X1050889Y0780006*
X1050535Y0780535*
X1050006Y0780889*
X1049382Y0781013*
G37*
G36*
X08137Y0777331D02*
X0813076Y0777207D01*
X0812547Y0776854*
X0812193Y0776324*
X0812069Y07757*
X0812193Y0775076*
X0812547Y0774546*
X0813076Y0774193*
X08137Y0774069*
X0814324Y0774193*
X0814853Y0774546*
X0815207Y0775076*
X0815331Y07757*
X0815207Y0776324*
X0814853Y0776854*
X0814324Y0777207*
X08137Y0777331*
G37*
G36*
X08485Y0771631D02*
X0847876Y0771507D01*
X0847346Y0771153*
X0846993Y0770624*
X0846869Y077*
X0846993Y0769376*
X0847346Y0768847*
X0847848Y0768511*
X0847876Y0768298*
Y0768202*
X0847848Y0767989*
X0847346Y0767654*
X0846993Y0767124*
X0846869Y07665*
X0846993Y0765876*
X0847346Y0765346*
X0847876Y0764993*
X08485Y0764869*
X0849124Y0764993*
X0849654Y0765346*
X0850007Y0765876*
X0850131Y07665*
X0850007Y0767124*
X0849654Y0767654*
X0849152Y0767989*
X0849124Y0768202*
Y0768298*
X0849152Y0768511*
X0849654Y0768847*
X0850007Y0769376*
X0850131Y077*
X0850007Y0770624*
X0849654Y0771153*
X0849124Y0771507*
X08485Y0771631*
G37*
G36*
X08949Y0764131D02*
X0894276Y0764007D01*
X0893746Y0763654*
X0893393Y0763124*
X0893269Y07625*
X0893393Y0761876*
X0893746Y0761346*
X0894276Y0760993*
X08949Y0760869*
X0895524Y0760993*
X0896054Y0761346*
X0896407Y0761876*
X0896531Y07625*
X0896407Y0763124*
X0896054Y0763654*
X0895524Y0764007*
X08949Y0764131*
G37*
G36*
X0841935D02*
X0841311Y0764007D01*
X0840781Y0763654*
X0840428Y0763124*
X0840304Y07625*
X0840428Y0761876*
X0840781Y0761346*
X0841311Y0760993*
X0841935Y0760869*
X0842559Y0760993*
X0843089Y0761346*
X0843442Y0761876*
X0843566Y07625*
X0843442Y0763124*
X0843089Y0763654*
X0842559Y0764007*
X0841935Y0764131*
G37*
G36*
X082425Y0763381D02*
X0823626Y0763257D01*
X0823096Y0762903*
X0822743Y0762374*
X0822619Y076175*
X0822743Y0761126*
X0822991Y0760755*
X0822661Y0760348*
X082219Y0760441*
X0821566Y0760317*
X0821037Y0759964*
X0820683Y0759434*
X0820559Y075881*
X0820683Y0758186*
X0821037Y0757656*
X0821566Y0757303*
X082219Y0757179*
X0822814Y0757303*
X0823343Y0757656*
X0823697Y0758186*
X0823821Y075881*
X0823697Y0759434*
X082345Y0759805*
X0823779Y0760212*
X082425Y0760119*
X0824874Y0760243*
X0825403Y0760597*
X0825757Y0761126*
X0825881Y076175*
X0825757Y0762374*
X0825403Y0762903*
X0824874Y0763257*
X082425Y0763381*
G37*
G36*
X08812Y0762131D02*
X0880576Y0762007D01*
X0880046Y0761654*
X0879693Y0761124*
X0879569Y07605*
X0879693Y0759876*
X0880046Y0759346*
X0880576Y0758993*
X08812Y0758869*
X0881824Y0758993*
X0882353Y0759346*
X0882707Y0759876*
X0882831Y07605*
X0882707Y0761124*
X0882353Y0761654*
X0881824Y0762007*
X08812Y0762131*
G37*
G36*
X09614Y0760731D02*
X0960776Y0760607D01*
X0960246Y0760253*
X0959893Y0759724*
X0959769Y07591*
X0959893Y0758476*
X0960246Y0757946*
X0960776Y0757593*
X09614Y0757469*
X0962024Y0757593*
X0962554Y0757946*
X0962907Y0758476*
X0963031Y07591*
X0962907Y0759724*
X0962554Y0760253*
X0962024Y0760607*
X09614Y0760731*
G37*
G36*
X0957Y0760631D02*
X0956376Y0760507D01*
X0955847Y0760153*
X0955493Y0759624*
X0955369Y0759*
X0955493Y0758376*
X0955847Y0757846*
X0956376Y0757493*
X0957Y0757369*
X0957624Y0757493*
X0958154Y0757846*
X0958507Y0758376*
X0958631Y0759*
X0958507Y0759624*
X0958154Y0760153*
X0957624Y0760507*
X0957Y0760631*
G37*
G36*
X1028878Y0764517D02*
X102769Y0764361D01*
X1026584Y0763902*
X1025633Y0763173*
X1024904Y0762223*
X1024445Y0761116*
X1024289Y0759928*
X1024445Y075874*
X1024904Y0757633*
X1025633Y0756683*
X1026584Y0755954*
X102769Y0755495*
X1028878Y0755339*
X1030066Y0755495*
X1031173Y0755954*
X1032123Y0756683*
X1032853Y0757633*
X1033311Y075874*
X1033467Y0759928*
X1033311Y0761116*
X1032853Y0762223*
X1032123Y0763173*
X1031173Y0763902*
X1030066Y0764361*
X1028878Y0764517*
G37*
G36*
X1017067D02*
X1015879Y0764361D01*
X1014773Y0763902*
X1013822Y0763173*
X1013093Y0762223*
X1012634Y0761116*
X1012478Y0759928*
X1012634Y075874*
X1013093Y0757633*
X1013822Y0756683*
X1014773Y0755954*
X1015879Y0755495*
X1017067Y0755339*
X1018255Y0755495*
X1019362Y0755954*
X1020312Y0756683*
X1021042Y0757633*
X10215Y075874*
X1021657Y0759928*
X10215Y0761116*
X1021042Y0762223*
X1020312Y0763173*
X1019362Y0763902*
X1018255Y0764361*
X1017067Y0764517*
G37*
G36*
X1005256D02*
X1004068Y0764361D01*
X1002962Y0763902*
X1002011Y0763173*
X1001282Y0762223*
X1000823Y0761116*
X1000667Y0759928*
X1000823Y075874*
X1001282Y0757633*
X1002011Y0756683*
X1002962Y0755954*
X1004068Y0755495*
X1005256Y0755339*
X1006444Y0755495*
X1007551Y0755954*
X1008501Y0756683*
X1009231Y0757633*
X1009689Y075874*
X1009845Y0759928*
X1009689Y0761116*
X1009231Y0762223*
X1008501Y0763173*
X1007551Y0763902*
X1006444Y0764361*
X1005256Y0764517*
G37*
G36*
X12275Y0752131D02*
X1226876Y0752007D01*
X1226346Y0751653*
X1225993Y0751124*
X1225869Y07505*
X1225993Y0749876*
X1226346Y0749346*
X1226876Y0748993*
X12275Y0748869*
X1228124Y0748993*
X1228654Y0749346*
X1229007Y0749876*
X1229131Y07505*
X1229007Y0751124*
X1228654Y0751653*
X1228124Y0752007*
X12275Y0752131*
G37*
G36*
X07011Y0750131D02*
X0700476Y0750007D01*
X0699946Y0749653*
X0699593Y0749124*
X0699469Y07485*
X0699593Y0747876*
X0699946Y0747346*
X0700476Y0746993*
X07011Y0746869*
X0701724Y0746993*
X0702253Y0747346*
X0702607Y0747876*
X0702731Y07485*
X0702607Y0749124*
X0702253Y0749653*
X0701724Y0750007*
X07011Y0750131*
G37*
G36*
X08615Y0748131D02*
X0860876Y0748007D01*
X0860347Y0747653*
X0859993Y0747124*
X0859869Y07465*
X0859993Y0745876*
X0860009Y0745851*
X0859649Y0745491*
X0859624Y0745507*
X0859Y0745631*
X0858376Y0745507*
X0857847Y0745154*
X0857493Y0744624*
X0857369Y0744*
X0857462Y0743531*
X0857414Y0743446*
X0857154Y0743186*
X0857069Y0743138*
X08566Y0743231*
X0855976Y0743107*
X0855447Y0742754*
X0855093Y0742224*
X0854969Y07416*
X0855093Y0740976*
X0855447Y0740447*
X0855976Y0740093*
X08566Y0739969*
X0857224Y0740093*
X0857753Y0740447*
X0858107Y0740976*
X0858231Y07416*
X0858138Y0742069*
X0858186Y0742154*
X0858446Y0742414*
X0858531Y0742462*
X0859Y0742369*
X0859624Y0742493*
X0860153Y0742846*
X0860507Y0743376*
X0860631Y0744*
X0860507Y0744624*
X0860491Y0744649*
X0860851Y0745009*
X0860876Y0744993*
X08615Y0744869*
X0862124Y0744993*
X0862654Y0745346*
X0863007Y0745876*
X0863131Y07465*
X0863007Y0747124*
X0862654Y0747653*
X0862124Y0748007*
X08615Y0748131*
G37*
G36*
X0826219Y0748412D02*
X0825595Y0748288D01*
X0825066Y0747934*
X0824712Y0747405*
X0824588Y0746781*
X0824712Y0746157*
X0825066Y0745627*
X0825595Y0745274*
X0826219Y074515*
X0826843Y0745274*
X0827372Y0745627*
X0827726Y0746157*
X082785Y0746781*
X0827726Y0747405*
X0827372Y0747934*
X0826843Y0748288*
X0826219Y0748412*
G37*
G36*
X08516Y0748331D02*
X0850976Y0748207D01*
X0850447Y0747854*
X0850093Y0747324*
X0849969Y07467*
X0850093Y0746076*
X0850447Y0745546*
X0850976Y0745193*
X08516Y0745069*
X0852224Y0745193*
X0852754Y0745546*
X0853107Y0746076*
X0853231Y07467*
X0853107Y0747324*
X0852754Y0747854*
X0852224Y0748207*
X08516Y0748331*
G37*
G36*
X1156831Y0753887D02*
X1155643Y0753731D01*
X1154536Y0753272*
X1153586Y0752543*
X1152857Y0751593*
X1152398Y0750486*
X1152242Y0749298*
X1152398Y074811*
X1152857Y0747003*
X1153586Y0746053*
X1154536Y0745324*
X1155643Y0744865*
X1156831Y0744709*
X1158019Y0744865*
X1159126Y0745324*
X1160076Y0746053*
X1160805Y0747003*
X1161264Y074811*
X116142Y0749298*
X1161264Y0750486*
X1160805Y0751593*
X1160076Y0752543*
X1159126Y0753272*
X1158019Y0753731*
X1156831Y0753887*
G37*
G36*
X08939Y0747631D02*
X0893276Y0747507D01*
X0892747Y0747154*
X0892393Y0746624*
X0892269Y0746*
X0892393Y0745376*
X0892747Y0744846*
X0893276Y0744493*
X08939Y0744369*
X0894524Y0744493*
X0895053Y0744846*
X0895407Y0745376*
X0895531Y0746*
X0895407Y0746624*
X0895053Y0747154*
X0894524Y0747507*
X08939Y0747631*
G37*
G36*
X0898069Y0746167D02*
X0897334Y0746021D01*
X0896711Y0745605*
X0896295Y0744982*
X0896149Y0744247*
X0896295Y0743512*
X0896711Y0742889*
X0897334Y0742473*
X0898069Y0742327*
X0898804Y0742473*
X0899427Y0742889*
X0899843Y0743512*
X0899989Y0744247*
X0899843Y0744982*
X0899427Y0745605*
X0898804Y0746021*
X0898069Y0746167*
G37*
G36*
X0819329D02*
X0818594Y0746021D01*
X0817971Y0745605*
X0817555Y0744982*
X0817409Y0744247*
X0817555Y0743512*
X0817971Y0742889*
X0818594Y0742473*
X0819329Y0742327*
X0820064Y0742473*
X0820687Y0742889*
X0821103Y0743512*
X0821249Y0744247*
X0821103Y0744982*
X0820687Y0745605*
X0820064Y0746021*
X0819329Y0746167*
G37*
G36*
X096081Y0755761D02*
X0959496Y0755631D01*
X0958232Y0755248*
X0957067Y0754625*
X0956046Y0753787*
X0955208Y0752766*
X0954585Y0751602*
X0954202Y0750338*
X0954072Y0749023*
X0954202Y0747709*
X0954585Y0746445*
X0955208Y074528*
X0956046Y0744259*
X0957067Y0743421*
X0958232Y0742798*
X0959496Y0742415*
X096081Y0742285*
X0962125Y0742415*
X0963389Y0742798*
X0964553Y0743421*
X0965574Y0744259*
X0966412Y074528*
X0967035Y0746445*
X0967418Y0747709*
X0967548Y0749023*
X0967418Y0750338*
X0967035Y0751602*
X0966412Y0752766*
X0965574Y0753787*
X0964553Y0754625*
X0963389Y0755248*
X0962125Y0755631*
X096081Y0755761*
G37*
G36*
X076421D02*
X0762895Y0755631D01*
X0761631Y0755248*
X0760467Y0754625*
X0759446Y0753787*
X0758608Y0752766*
X0757985Y0751602*
X0757601Y0750338*
X0757472Y0749023*
X0757601Y0747709*
X0757985Y0746445*
X0758608Y074528*
X0759446Y0744259*
X0760467Y0743421*
X0761631Y0742798*
X0762895Y0742415*
X076421Y0742285*
X0765524Y0742415*
X0766788Y0742798*
X0767953Y0743421*
X0768974Y0744259*
X0769812Y074528*
X0770435Y0746445*
X0770819Y0747709*
X0770948Y0749023*
X0770819Y0750338*
X0770435Y0751602*
X0769812Y0752766*
X0768974Y0753787*
X0767953Y0754625*
X0766788Y0755248*
X0765524Y0755631*
X076421Y0755761*
G37*
G36*
X0619Y0754931D02*
X0617745Y0754807D01*
X0616539Y0754441*
X0615427Y0753847*
X0614453Y0753047*
X0613653Y0752073*
X0613059Y0750961*
X0612693Y0749755*
X0612569Y07485*
X0612693Y0747245*
X0613059Y0746039*
X0613653Y0744927*
X0614453Y0743953*
X0615427Y0743153*
X0616539Y0742559*
X0617745Y0742193*
X0619Y0742069*
X0620255Y0742193*
X0621461Y0742559*
X0622573Y0743153*
X0623547Y0743953*
X0624347Y0744927*
X0624941Y0746039*
X0625307Y0747245*
X0625431Y07485*
X0625307Y0749755*
X0624941Y0750961*
X0624347Y0752073*
X0623547Y0753047*
X0622573Y0753847*
X0621461Y0754441*
X0620255Y0754807*
X0619Y0754931*
G37*
G36*
X08885Y0745131D02*
X0887876Y0745007D01*
X0887346Y0744654*
X0886993Y0744124*
X0886869Y07435*
X0886993Y0742876*
X0887346Y0742346*
X0887876Y0741993*
X08885Y0741869*
X0889124Y0741993*
X0889653Y0742346*
X0889746*
X0889946Y0742046*
X0890476Y0741693*
X08911Y0741569*
X0891724Y0741693*
X0892253Y0742046*
X0892607Y0742576*
X0892731Y07432*
X0892607Y0743824*
X0892253Y0744353*
X0891724Y0744707*
X08911Y0744831*
X0890476Y0744707*
X0889946Y0744353*
X0889854*
X0889653Y0744654*
X0889124Y0745007*
X08885Y0745131*
G37*
G36*
X1003Y0742631D02*
X1002376Y0742507D01*
X1001847Y0742154*
X1001493Y0741624*
X1001369Y0741*
X1001493Y0740376*
X1001847Y0739847*
X1002376Y0739493*
X1003Y0739369*
X1003624Y0739493*
X1004154Y0739847*
X1004507Y0740376*
X1004631Y0741*
X1004507Y0741624*
X1004154Y0742154*
X1003624Y0742507*
X1003Y0742631*
G37*
G36*
X09489Y0736131D02*
X0948276Y0736007D01*
X0947746Y0735653*
X0947393Y0735124*
X0947269Y07345*
X0947393Y0733876*
X0947746Y0733347*
X0948276Y0732993*
X09489Y0732869*
X0949524Y0732993*
X0950054Y0733347*
X0950407Y0733876*
X0950531Y07345*
X0950407Y0735124*
X0950054Y0735653*
X0949524Y0736007*
X09489Y0736131*
G37*
G36*
X08717Y0731331D02*
X0871076Y0731207D01*
X0870547Y0730854*
X0870333Y0730534*
X0869924Y0730807*
X08693Y0730931*
X0868676Y0730807*
X0868147Y0730453*
X0867793Y0729924*
X0867705Y0729485*
X0867231Y07295*
X0867107Y0730124*
X0866753Y0730653*
X0866224Y0731007*
X08656Y0731131*
X0864976Y0731007*
X0864447Y0730653*
X0864093Y0730124*
X0863969Y07295*
X086385Y0729382*
X08636Y0729431*
X0862976Y0729307*
X0862446Y0728954*
X0862093Y0728424*
X0861969Y07278*
X0862093Y0727176*
X0862446Y0726647*
X0862976Y0726293*
X08636Y0726169*
X0864224Y0726293*
X0864754Y0726647*
X0865107Y0727176*
X0865231Y07278*
X086535Y0727918*
X08656Y0727869*
X0866224Y0727993*
X0866753Y0728346*
X0867107Y0728876*
X0867195Y0729315*
X0867669Y07293*
X0867793Y0728676*
X0868147Y0728147*
X0868676Y0727793*
X08693Y0727669*
X0869924Y0727793*
X0870453Y0728147*
X0870667Y0728466*
X0871076Y0728193*
X08717Y0728069*
X0872324Y0728193*
X0872853Y0728546*
X0873207Y0729076*
X0873331Y07297*
X0873207Y0730324*
X0872853Y0730854*
X0872324Y0731207*
X08717Y0731331*
G37*
G36*
X08466Y0731131D02*
X0845976Y0731007D01*
X0845446Y0730653*
X0845249Y0730358*
X0844724Y0730107*
X08441Y0730231*
X0843476Y0730107*
X0842947Y0729753*
X0842593Y0729224*
X0842469Y07286*
X0842593Y0727976*
X0842947Y0727447*
X0843476Y0727093*
X08441Y0726969*
X0844724Y0727093*
X0845253Y0727447*
X0845607Y0727976*
X0846115Y0727965*
X08466Y0727869*
X0847224Y0727993*
X0847754Y0728346*
X0848107Y0728876*
X0848231Y07295*
X0848107Y0730124*
X0847754Y0730653*
X0847224Y0731007*
X08466Y0731131*
G37*
G36*
X08794Y0732731D02*
X0878776Y0732607D01*
X0878246Y0732254*
X0877893Y0731724*
X0877769Y07311*
X0877893Y0730476*
X0878246Y0729947*
X0878776Y0729593*
X08794Y0729469*
X0880024Y0729593*
X0880554Y0729947*
X0880907Y0730476*
X0881031Y07311*
X0880907Y0731724*
X0880554Y0732254*
X0880024Y0732607*
X08794Y0732731*
G37*
G36*
X08976Y0730731D02*
X0896976Y0730607D01*
X0896447Y0730254*
X0896093Y0729724*
X0895969Y07291*
X0896093Y0728476*
X0896447Y0727947*
X0896976Y0727593*
X08976Y0727469*
X0898224Y0727593*
X0898754Y0727947*
X0899107Y0728476*
X0899231Y07291*
X0899107Y0729724*
X0898754Y0730254*
X0898224Y0730607*
X08976Y0730731*
G37*
G36*
X08933Y0730631D02*
X0892676Y0730507D01*
X0892146Y0730154*
X0891793Y0729624*
X0891669Y0729*
X0891793Y0728376*
X0892146Y0727846*
X0892676Y0727493*
X08933Y0727369*
X0893924Y0727493*
X0894454Y0727846*
X0894807Y0728376*
X0894931Y0729*
X0894807Y0729624*
X0894454Y0730154*
X0893924Y0730507*
X08933Y0730631*
G37*
G36*
X084Y0733431D02*
X0839376Y0733307D01*
X0838846Y0732954*
X0838493Y0732424*
X0838369Y07318*
X0838493Y0731176*
X0838846Y0730647*
X083899Y0730551*
Y0729949*
X0838846Y0729853*
X0838493Y0729324*
X0838369Y07287*
X0838493Y0728076*
X0838846Y0727547*
X0839376Y0727193*
X084Y0727069*
X0840624Y0727193*
X0841154Y0727547*
X0841507Y0728076*
X0841631Y07287*
X0841507Y0729324*
X0841154Y0729853*
X084101Y0729949*
Y0730551*
X0841154Y0730647*
X0841507Y0731176*
X0841631Y07318*
X0841507Y0732424*
X0841154Y0732954*
X0840624Y0733307*
X084Y0733431*
G37*
G36*
X0857Y0730131D02*
X0856376Y0730007D01*
X0855847Y0729654*
X0855493Y0729124*
X0855369Y07285*
X0855493Y0727876*
X0855847Y0727347*
X0856376Y0726993*
X0857Y0726869*
X0857624Y0726993*
X0858154Y0727347*
X0858507Y0727876*
X0858631Y07285*
X0858507Y0729124*
X0858154Y0729654*
X0857624Y0730007*
X0857Y0730131*
G37*
G36*
X09333Y0728331D02*
X0932676Y0728207D01*
X0932146Y0727853*
X0931793Y0727324*
X0931669Y07267*
X0931793Y0726076*
X0932146Y0725547*
X0932676Y0725193*
X09333Y0725069*
X0933924Y0725193*
X0934453Y0725547*
X0934807Y0726076*
X0934931Y07267*
X0934807Y0727324*
X0934453Y0727853*
X0933924Y0728207*
X09333Y0728331*
G37*
G36*
X08832D02*
X0882576Y0728207D01*
X0882047Y0727853*
X0881693Y0727324*
X0881569Y07267*
X0881693Y0726076*
X0882047Y0725547*
X0882576Y0725193*
X08832Y0725069*
X0883824Y0725193*
X0884354Y0725547*
X0884707Y0726076*
X0884831Y07267*
X0884707Y0727324*
X0884354Y0727853*
X0883824Y0728207*
X08832Y0728331*
G37*
G36*
X11625Y0725631D02*
X1161876Y0725507D01*
X1161347Y0725153*
X1160993Y0724624*
X1160869Y0724*
X1160993Y0723376*
X1161347Y0722847*
X1161876Y0722493*
X11625Y0722369*
X1163124Y0722493*
X1163653Y0722847*
X1164007Y0723376*
X1164131Y0724*
X1164007Y0724624*
X1163653Y0725153*
X1163124Y0725507*
X11625Y0725631*
G37*
G36*
X0849D02*
X0848376Y0725507D01*
X0847847Y0725153*
X0847493Y0724624*
X0847369Y0724*
X0847493Y0723376*
X0847847Y0722847*
X0848376Y0722493*
X0849Y0722369*
X0849624Y0722493*
X0850154Y0722847*
X0850507Y0723376*
X0850631Y0724*
X0850507Y0724624*
X0850154Y0725153*
X0849624Y0725507*
X0849Y0725631*
G37*
G36*
X08321Y0723531D02*
X0831476Y0723407D01*
X0830947Y0723054*
X0830593Y0722524*
X0830469Y07219*
X0830593Y0721276*
X0830947Y0720747*
X0831476Y0720393*
X08321Y0720269*
X0832724Y0720393*
X0833253Y0720747*
X0833607Y0721276*
X0833731Y07219*
X0833607Y0722524*
X0833253Y0723054*
X0832724Y0723407*
X08321Y0723531*
G37*
G36*
X11568Y0723431D02*
X1156176Y0723307D01*
X1155647Y0722954*
X1155293Y0722424*
X1155169Y07218*
X1155293Y0721176*
X1155647Y0720646*
X1156176Y0720293*
X11568Y0720169*
X1157424Y0720293*
X1157953Y0720646*
X1158307Y0721176*
X1158431Y07218*
X1158307Y0722424*
X1157953Y0722954*
X1157424Y0723307*
X11568Y0723431*
G37*
G36*
X12415Y0720131D02*
X1240876Y0720007D01*
X1240347Y0719654*
X1239993Y0719124*
X1239869Y07185*
X1239993Y0717876*
X1240347Y0717346*
X1240876Y0716993*
X12415Y0716869*
X1242124Y0716993*
X1242653Y0717346*
X1243007Y0717876*
X1243131Y07185*
X1243007Y0719124*
X1242653Y0719654*
X1242124Y0720007*
X12415Y0720131*
G37*
G36*
X07745Y0714631D02*
X0773876Y0714507D01*
X0773347Y0714153*
X0772993Y0713624*
X0772869Y0713*
X0772993Y0712376*
X0773347Y0711846*
X0773876Y0711493*
X07745Y0711369*
X0775124Y0711493*
X0775654Y0711846*
X0776007Y0712376*
X0776131Y0713*
X0776007Y0713624*
X0775654Y0714153*
X0775124Y0714507*
X07745Y0714631*
G37*
G36*
X0761Y0714131D02*
X0760376Y0714007D01*
X0759846Y0713654*
X0759493Y0713124*
X0759369Y07125*
X0759493Y0711876*
X0759846Y0711346*
X0760376Y0710993*
X0761Y0710869*
X0761624Y0710993*
X0762153Y0711346*
X0762507Y0711876*
X0762631Y07125*
X0762507Y0713124*
X0762153Y0713654*
X0761624Y0714007*
X0761Y0714131*
G37*
G36*
X0768699Y0712037D02*
X0767964Y0711891D01*
X0767341Y0711475*
X0766925Y0710852*
X0766779Y0710117*
X0766925Y0709382*
X0767341Y0708759*
X0767964Y0708343*
X0768699Y0708197*
X0769434Y0708343*
X0770057Y0708759*
X0770473Y0709382*
X0770619Y0710117*
X0770473Y0710852*
X0770057Y0711475*
X0769434Y0711891*
X0768699Y0712037*
G37*
G36*
X07875Y0709131D02*
X0786876Y0709007D01*
X0786346Y0708653*
X0785993Y0708124*
X0785869Y07075*
X0785993Y0706876*
X0786346Y0706347*
X0786876Y0705993*
X07875Y0705869*
X0788124Y0705993*
X0788654Y0706347*
X0789007Y0706876*
X0789131Y07075*
X0789007Y0708124*
X0788654Y0708653*
X0788124Y0709007*
X07875Y0709131*
G37*
G36*
X0755836Y0708795D02*
X0755212Y0708671D01*
X0754682Y0708318*
X0754329Y0707788*
X0754205Y0707164*
X0754329Y070654*
X0754682Y070601*
X0755212Y0705657*
X0755836Y0705533*
X075646Y0705657*
X0756989Y070601*
X0757343Y070654*
X0757467Y0707164*
X0757343Y0707788*
X0756989Y0708318*
X075646Y0708671*
X0755836Y0708795*
G37*
G36*
X095619Y0712033D02*
X0955455Y0711887D01*
X0954832Y0711471*
X0954416Y0710848*
X095427Y0710113*
X0954416Y0709378*
X0954832Y0708755*
X0955455Y0708339*
X0955823Y0708266*
Y0707756*
X0955576Y0707707*
X0955046Y0707353*
X0954693Y0706824*
X0954569Y07062*
X0954693Y0705576*
X0954858Y0705329*
X0955008Y070495*
X0954858Y0704571*
X0954693Y0704324*
X0954569Y07037*
X0954693Y0703076*
X0955046Y0702547*
X0955576Y0702193*
X09562Y0702069*
X0956824Y0702193*
X0957353Y0702547*
X0957707Y0703076*
X0957831Y07037*
X0957707Y0704324*
X0957542Y0704571*
X0957392Y070495*
X0957542Y0705329*
X0957707Y0705576*
X0957831Y07062*
X0957707Y0706824*
X0957353Y0707353*
X0956824Y0707707*
X0956567Y0707758*
Y0708268*
X0956925Y0708339*
X0957548Y0708755*
X0957964Y0709378*
X095811Y0710113*
X0957964Y0710848*
X0957548Y0711471*
X0956925Y0711887*
X095619Y0712033*
G37*
G36*
X084Y0698731D02*
X0839376Y0698607D01*
X0838846Y0698253*
X0838493Y0697724*
X0838369Y06971*
X0838493Y0696476*
X083863Y0696271*
X0838269Y069591*
X0838124Y0696007*
X08375Y0696131*
X0836876Y0696007*
X0836347Y0695653*
X0835993Y0695124*
X0835869Y06945*
X0835993Y0693876*
X0836347Y0693347*
X0836876Y0692993*
X08375Y0692869*
X0838124Y0692993*
X0838653Y0693347*
X0839007Y0693876*
X0839131Y06945*
X0839007Y0695124*
X083887Y0695329*
X0839231Y069569*
X0839376Y0695593*
X084Y0695469*
X0840624Y0695593*
X0841154Y0695947*
X0841507Y0696476*
X0841631Y06971*
X0841507Y0697724*
X0841154Y0698253*
X0840624Y0698607*
X084Y0698731*
G37*
G36*
X09289Y0699131D02*
X0928276Y0699007D01*
X0927746Y0698654*
X0927393Y0698124*
X0927269Y06975*
X0927393Y0696876*
X0927746Y0696347*
X0928276Y0695993*
X09289Y0695869*
X0929524Y0695993*
X0930054Y0696347*
X0930407Y0696876*
X0930531Y06975*
X0930407Y0698124*
X0930054Y0698654*
X0929524Y0699007*
X09289Y0699131*
G37*
G36*
X07Y0697631D02*
X0699376Y0697507D01*
X0698846Y0697154*
X0698493Y0696624*
X0698369Y0696*
X0698493Y0695376*
X0698846Y0694846*
X0699376Y0694493*
X07Y0694369*
X0700624Y0694493*
X0701154Y0694846*
X0701507Y0695376*
X0701631Y0696*
X0701507Y0696624*
X0701154Y0697154*
X0700624Y0697507*
X07Y0697631*
G37*
G36*
X0829Y0693631D02*
X0828376Y0693507D01*
X0827847Y0693153*
X0827493Y0692624*
X0827369Y0692*
X0827493Y0691376*
X0827847Y0690846*
X0828376Y0690493*
X0829Y0690369*
X0829624Y0690493*
X0830153Y0690846*
X0830507Y0691376*
X0830631Y0692*
X0830507Y0692624*
X0830153Y0693153*
X0829624Y0693507*
X0829Y0693631*
G37*
G36*
X0619Y0702431D02*
X0617745Y0702307D01*
X0616539Y0701941*
X0615427Y0701347*
X0614453Y0700547*
X0613653Y0699573*
X0613059Y0698461*
X0612693Y0697255*
X0612569Y0696*
X0612693Y0694745*
X0613059Y0693539*
X0613653Y0692427*
X0614453Y0691453*
X0615427Y0690653*
X0616539Y0690059*
X0617745Y0689693*
X0619Y0689569*
X0620255Y0689693*
X0621461Y0690059*
X0622573Y0690653*
X0623547Y0691453*
X0624347Y0692427*
X0624941Y0693539*
X0625307Y0694745*
X0625431Y0696*
X0625307Y0697255*
X0624941Y0698461*
X0624347Y0699573*
X0623547Y0700547*
X0622573Y0701347*
X0621461Y0701941*
X0620255Y0702307*
X0619Y0702431*
G37*
G36*
X09545Y0691131D02*
X0953876Y0691007D01*
X0953347Y0690654*
X0952993Y0690124*
X0952869Y06895*
X0952993Y0688876*
X0953347Y0688346*
X0953876Y0687993*
X09545Y0687869*
X0955124Y0687993*
X0955653Y0688346*
X0956007Y0688876*
X0956131Y06895*
X0956007Y0690124*
X0955653Y0690654*
X0955124Y0691007*
X09545Y0691131*
G37*
G36*
X09383Y0689131D02*
X0937676Y0689007D01*
X0937146Y0688654*
X0936793Y0688124*
X0936669Y06875*
X0936793Y0686876*
X0937146Y0686346*
X0937676Y0685993*
X09383Y0685869*
X0938924Y0685993*
X0939454Y0686346*
X0939807Y0686876*
X0939931Y06875*
X0939807Y0688124*
X0939454Y0688654*
X0938924Y0689007*
X09383Y0689131*
G37*
G36*
X0942941Y0689119D02*
X0942317Y0688995D01*
X0941787Y0688641*
X0941434Y0688112*
X094131Y0687488*
X0941434Y0686863*
X0941787Y0686334*
X0942317Y068598*
X0942941Y0685856*
X0943565Y068598*
X0944094Y0686334*
X0944448Y0686863*
X0944572Y0687488*
X0944448Y0688112*
X0944094Y0688641*
X0943565Y0688995*
X0942941Y0689119*
G37*
G36*
X09795Y0686031D02*
X0978876Y0685907D01*
X0978347Y0685554*
X0977993Y0685024*
X0977869Y06844*
X0977993Y0683776*
X0978347Y0683247*
X0978876Y0682893*
X09795Y0682769*
X0980124Y0682893*
X0980653Y0683247*
X0981007Y0683776*
X0981131Y06844*
X0981007Y0685024*
X0980653Y0685554*
X0980124Y0685907*
X09795Y0686031*
G37*
G36*
X0931933Y0684631D02*
X0931309Y0684507D01*
X0930779Y0684154*
X0930426Y0683624*
X0930302Y0683*
X0930426Y0682376*
X0930779Y0681847*
X0931309Y0681493*
X0931933Y0681369*
X0932557Y0681493*
X0933086Y0681847*
X093344Y0682376*
X0933564Y0683*
X093344Y0683624*
X0933086Y0684154*
X0932557Y0684507*
X0931933Y0684631*
G37*
G36*
X09935Y0683631D02*
X0992876Y0683507D01*
X0992346Y0683153*
X0991993Y0682624*
X0991869Y0682*
X0991993Y0681376*
X0992346Y0680847*
X0992876Y0680493*
X09935Y0680369*
X0994124Y0680493*
X0994654Y0680847*
X0995007Y0681376*
X0995131Y0682*
X0995007Y0682624*
X0994654Y0683153*
X0994124Y0683507*
X09935Y0683631*
G37*
G36*
X0787009Y0683205D02*
X0786385Y0683081D01*
X0785856Y0682727*
X0785502Y0682198*
X0785378Y0681574*
X0785502Y068095*
X0785856Y068042*
X0786385Y0680067*
X0787009Y0679943*
X0787634Y0680067*
X0788163Y068042*
X0788517Y068095*
X0788641Y0681574*
X0788517Y0682198*
X0788163Y0682727*
X0787634Y0683081*
X0787009Y0683205*
G37*
G36*
X09268Y0682531D02*
X0926176Y0682407D01*
X0925646Y0682054*
X0925293Y0681524*
X0925169Y06809*
X0925293Y0680276*
X0925646Y0679746*
X0926176Y0679393*
X09268Y0679269*
X0927424Y0679393*
X0927954Y0679746*
X0928307Y0680276*
X0928431Y06809*
X0928307Y0681524*
X0927954Y0682054*
X0927424Y0682407*
X09268Y0682531*
G37*
G36*
X10055Y0681631D02*
X1004876Y0681507D01*
X1004346Y0681153*
X1003993Y0680624*
X1003869Y068*
X1003993Y0679376*
X1004346Y0678847*
X1004876Y0678493*
X10055Y0678369*
X1006124Y0678493*
X1006653Y0678847*
X1007007Y0679376*
X1007131Y068*
X1007007Y0680624*
X1006653Y0681153*
X1006124Y0681507*
X10055Y0681631*
G37*
G36*
X0857Y0681031D02*
X0856376Y0680907D01*
X0855847Y0680553*
X0855493Y0680024*
X0855369Y06794*
X0855493Y0678776*
X0855847Y0678246*
X0856376Y0677893*
X0857Y0677769*
X0857624Y0677893*
X0858154Y0678246*
X0858507Y0678776*
X0858631Y06794*
X0858507Y0680024*
X0858154Y0680553*
X0857624Y0680907*
X0857Y0681031*
G37*
G36*
X08617Y0679031D02*
X0861076Y0678907D01*
X0860546Y0678553*
X0860193Y0678024*
X0860069Y06774*
X0860193Y0676776*
X0860546Y0676247*
X0861076Y0675893*
X08617Y0675769*
X0862324Y0675893*
X0862854Y0676247*
X0863207Y0676776*
X0863331Y06774*
X0863207Y0678024*
X0862854Y0678553*
X0862324Y0678907*
X08617Y0679031*
G37*
G36*
X0971Y0678631D02*
X0970376Y0678507D01*
X0969847Y0678154*
X0969493Y0677624*
X0969369Y0677*
X0969493Y0676376*
X0969847Y0675846*
X0970376Y0675493*
X0971Y0675369*
X0971624Y0675493*
X0972153Y0675846*
X0972507Y0676376*
X0972631Y0677*
X0972507Y0677624*
X0972153Y0678154*
X0971624Y0678507*
X0971Y0678631*
G37*
G36*
X0854Y0677531D02*
X0853376Y0677407D01*
X0852847Y0677053*
X0852493Y0676524*
X0852369Y06759*
X0852493Y0675276*
X0852847Y0674747*
X0853376Y0674393*
X0854Y0674269*
X0854624Y0674393*
X0855153Y0674747*
X0855507Y0675276*
X0855631Y06759*
X0855507Y0676524*
X0855153Y0677053*
X0854624Y0677407*
X0854Y0677531*
G37*
G36*
X10125Y0677131D02*
X1011876Y0677007D01*
X1011347Y0676653*
X1010993Y0676124*
X1010869Y06755*
X1010993Y0674876*
X1011347Y0674346*
X1011876Y0673993*
X10125Y0673869*
X1013124Y0673993*
X1013653Y0674346*
X1014007Y0674876*
X1014131Y06755*
X1014007Y0676124*
X1013653Y0676653*
X1013124Y0677007*
X10125Y0677131*
G37*
G36*
X08595Y0675431D02*
X0858876Y0675307D01*
X0858346Y0674954*
X0857993Y0674424*
X0857869Y06738*
X0857993Y0673176*
X0858346Y0672647*
X0858876Y0672293*
X08595Y0672169*
X0860124Y0672293*
X0860653Y0672647*
X0861007Y0673176*
X0861131Y06738*
X0861007Y0674424*
X0860653Y0674954*
X0860124Y0675307*
X08595Y0675431*
G37*
G36*
X0918742Y0673431D02*
X0918118Y0673307D01*
X0917589Y0672954*
X0917235Y0672424*
X0917111Y06718*
X0917235Y0671176*
X0917589Y0670646*
X0918118Y0670293*
X0918742Y0670169*
X0919366Y0670293*
X0919896Y0670646*
X0920249Y0671176*
X0920373Y06718*
X0920249Y0672424*
X0919896Y0672954*
X0919366Y0673307*
X0918742Y0673431*
G37*
G36*
X0958Y0673131D02*
X0957376Y0673007D01*
X0956847Y0672653*
X0956493Y0672124*
X0956369Y06715*
X0956493Y0670876*
X0956847Y0670346*
X0957376Y0669993*
X0958Y0669869*
X0958624Y0669993*
X0959153Y0670346*
X0959507Y0670876*
X0959631Y06715*
X0959507Y0672124*
X0959153Y0672653*
X0958624Y0673007*
X0958Y0673131*
G37*
G36*
X07884Y0671331D02*
X0787776Y0671207D01*
X0787247Y0670854*
X0786893Y0670324*
X0786769Y06697*
X0786893Y0669076*
X0787247Y0668546*
X0787776Y0668193*
X07884Y0668069*
X0789024Y0668193*
X0789553Y0668546*
X0789907Y0669076*
X0790031Y06697*
X0789907Y0670324*
X0789553Y0670854*
X0789024Y0671207*
X07884Y0671331*
G37*
G36*
X09794Y0671131D02*
X0978776Y0671007D01*
X0978246Y0670653*
X0977893Y0670124*
X0977769Y06695*
X0977893Y0668876*
X0978246Y0668347*
X0978776Y0667993*
X09794Y0667869*
X0980024Y0667993*
X0980554Y0668347*
X0980907Y0668876*
X0981031Y06695*
X0980907Y0670124*
X0980554Y0670653*
X0980024Y0671007*
X09794Y0671131*
G37*
G36*
X09715Y0669531D02*
X0970876Y0669407D01*
X0970347Y0669054*
X0969993Y0668524*
X0969869Y06679*
X0969993Y0667276*
X0970347Y0666747*
X0970876Y0666393*
X09715Y0666269*
X0972124Y0666393*
X0972653Y0666747*
X0973007Y0667276*
X0973131Y06679*
X0973007Y0668524*
X0972653Y0669054*
X0972124Y0669407*
X09715Y0669531*
G37*
G36*
X0781294Y0669425D02*
X078067Y0669301D01*
X078014Y0668948*
X0779787Y0668418*
X0779663Y0667794*
X0779787Y066717*
X078014Y0666641*
X078067Y0666287*
X0781294Y0666163*
X0781918Y0666287*
X0782447Y0666641*
X0782801Y066717*
X0782925Y0667794*
X0782801Y0668418*
X0782447Y0668948*
X0781918Y0669301*
X0781294Y0669425*
G37*
G36*
X0976402Y0668635D02*
X0975778Y0668511D01*
X0975249Y0668157*
X0974895Y0667628*
X0974771Y0667004*
X0974895Y066638*
X0975249Y066585*
X0975778Y0665497*
X0976402Y0665373*
X0977026Y0665497*
X0977556Y066585*
X0977909Y066638*
X0978033Y0667004*
X0977909Y0667628*
X0977556Y0668157*
X0977026Y0668511*
X0976402Y0668635*
G37*
G36*
X12835Y0668131D02*
X1282876Y0668007D01*
X1282347Y0667654*
X1281993Y0667124*
X1281869Y06665*
X1281993Y0665876*
X1282347Y0665346*
X1282876Y0664993*
X12835Y0664869*
X1284124Y0664993*
X1284653Y0665346*
X1285007Y0665876*
X1285131Y06665*
X1285007Y0667124*
X1284653Y0667654*
X1284124Y0668007*
X12835Y0668131*
G37*
G36*
X09215Y066816D02*
X0920876Y0668036D01*
X0920347Y0667682*
X0919993Y0667153*
X0919869Y0666528*
X0919993Y0665904*
X0920347Y0665375*
X0920876Y0665021*
X09215Y0664897*
X0922124Y0665021*
X0922565Y0665316*
X0922974Y0665364*
X0923208Y0665305*
X0923676Y0664993*
X09243Y0664869*
X0924924Y0664993*
X0925453Y0665346*
X0925807Y0665876*
X0925931Y06665*
X0925807Y0667124*
X0925453Y0667654*
X0924924Y0668007*
X09243Y0668131*
X0923676Y0668007*
X0923234Y0667712*
X0922826Y0667665*
X0922592Y0667723*
X0922124Y0668036*
X09215Y066816*
G37*
G36*
X08657Y0666031D02*
X0865076Y0665907D01*
X0864546Y0665554*
X0864193Y0665024*
X0864069Y06644*
X0864153Y0663977*
X0863807Y066358*
X0863765Y0663559*
X08634Y0663631*
X0862776Y0663507*
X0862247Y0663154*
X0861893Y0662624*
X0861769Y0662*
X0861893Y0661376*
X0862247Y0660847*
X0862776Y0660493*
X08634Y0660369*
X0864024Y0660493*
X0864554Y0660847*
X0864907Y0661376*
X0865031Y0662*
X0864947Y0662423*
X0865293Y066282*
X0865335Y0662841*
X08657Y0662769*
X0866324Y0662893*
X0866854Y0663246*
X0867207Y0663776*
X0867331Y06644*
X0867207Y0665024*
X0866854Y0665554*
X0866324Y0665907*
X08657Y0666031*
G37*
G36*
X10125Y0667131D02*
X1011876Y0667007D01*
X1011347Y0666653*
X1010993Y0666124*
X1010869Y06655*
X1010993Y0664876*
X1011347Y0664347*
X1011876Y0663993*
X101238Y0663893*
X1012592Y066356*
X1012644Y0663387*
X1012639Y066338*
X1012515Y0662756*
X1012639Y0662132*
X1012993Y0661602*
X1013522Y0661249*
X1014146Y0661125*
X1014771Y0661249*
X1015139Y0661495*
X10155Y0661135*
X1015493Y0661124*
X1015369Y06605*
X1015493Y0659876*
X1015847Y0659346*
X1016376Y0658993*
X1017Y0658869*
X1017624Y0658993*
X1018153Y0659346*
X1018507Y0659876*
X1018631Y06605*
X1018507Y0661124*
X1018153Y0661654*
X1017624Y0662007*
X1017Y0662131*
X1016376Y0662007*
X1016007Y0661761*
X1015647Y0662121*
X1015654Y0662132*
X1015778Y0662756*
X1015654Y066338*
X10153Y066391*
X1014771Y0664263*
X1014266Y0664363*
X1014054Y0664696*
X1014002Y0664868*
X1014007Y0664876*
X1014131Y06655*
X1014007Y0666124*
X1013653Y0666653*
X1013124Y0667007*
X10125Y0667131*
G37*
G36*
X0871Y0661131D02*
X0870376Y0661007D01*
X0869847Y0660653*
X0869493Y0660124*
X0869369Y06595*
X0869493Y0658876*
X0869847Y0658347*
X0870376Y0657993*
X0871Y0657869*
X0871624Y0657993*
X0872153Y0658347*
X0872507Y0658876*
X0872631Y06595*
X0872507Y0660124*
X0872153Y0660653*
X0871624Y0661007*
X0871Y0661131*
G37*
G36*
X09885Y0658631D02*
X0987876Y0658507D01*
X0987346Y0658153*
X0986993Y0657624*
X0986869Y0657*
X0986993Y0656376*
X0987346Y0655847*
X0987876Y0655493*
X09885Y0655369*
X0989124Y0655493*
X0989653Y0655847*
X0990007Y0656376*
X0990131Y0657*
X0990007Y0657624*
X0989653Y0658153*
X0989124Y0658507*
X09885Y0658631*
G37*
G36*
X0996Y0657231D02*
X0995376Y0657107D01*
X0994847Y0656753*
X0994493Y0656224*
X0994369Y06556*
X0994493Y0654976*
X0994847Y0654447*
X0995376Y0654093*
X0996Y0653969*
X0996624Y0654093*
X0996825Y0654227*
X0997327Y0654342*
X0997583Y0654189*
X0997876Y0653993*
X09985Y0653869*
X0999124Y0653993*
X0999654Y0654347*
X1000007Y0654876*
X1000131Y06555*
X1000007Y0656124*
X0999654Y0656653*
X0999124Y0657007*
X09985Y0657131*
X0997876Y0657007*
X0997675Y0656873*
X0997173Y0656758*
X0996917Y0656911*
X0996624Y0657107*
X0996Y0657231*
G37*
G36*
X10025Y0656631D02*
X1001876Y0656507D01*
X1001346Y0656153*
X1000993Y0655624*
X1000869Y0655*
X1000993Y0654376*
X1001346Y0653847*
X1001876Y0653493*
X10025Y0653369*
X1003124Y0653493*
X1003654Y0653847*
X1004007Y0654376*
X1004131Y0655*
X1004007Y0655624*
X1003654Y0656153*
X1003124Y0656507*
X10025Y0656631*
G37*
G36*
X09915Y0655631D02*
X0990876Y0655507D01*
X0990347Y0655154*
X0989993Y0654624*
X0989869Y0654*
X0989993Y0653376*
X0990347Y0652846*
X0990876Y0652493*
X09915Y0652369*
X0992124Y0652493*
X0992653Y0652846*
X0993007Y0653376*
X0993131Y0654*
X0993007Y0654624*
X0992653Y0655154*
X0992124Y0655507*
X09915Y0655631*
G37*
G36*
X08885Y0658131D02*
X0887876Y0658007D01*
X0887346Y0657654*
X0886993Y0657124*
X0886869Y06565*
X0886993Y0655876*
X0887346Y0655346*
X0887876Y0654993*
X08885Y0654869*
X0889124Y0654993*
X0889149Y0655009*
X0889509Y0654649*
X0889493Y0654624*
X0889369Y0654*
X0889493Y0653376*
X0889847Y0652846*
X0890376Y0652493*
X0891Y0652369*
X0891624Y0652493*
X0892153Y0652846*
X0892507Y0653376*
X0892631Y0654*
X0892507Y0654624*
X0892153Y0655154*
X0891624Y0655507*
X0891Y0655631*
X0890376Y0655507*
X0890351Y0655491*
X0889991Y0655851*
X0890007Y0655876*
X0890131Y06565*
X0890007Y0657124*
X0889653Y0657654*
X0889124Y0658007*
X08885Y0658131*
G37*
G36*
X0771Y0655631D02*
X0770376Y0655507D01*
X0769846Y0655154*
X0769493Y0654624*
X0769369Y0654*
X0769493Y0653376*
X0769846Y0652846*
X0770376Y0652493*
X0771Y0652369*
X0771624Y0652493*
X0772154Y0652846*
X0772507Y0653376*
X0772631Y0654*
X0772507Y0654624*
X0772154Y0655154*
X0771624Y0655507*
X0771Y0655631*
G37*
G36*
X0788746Y0653677D02*
X0788122Y0653553D01*
X0787593Y0653199*
X0787239Y065267*
X0787115Y0652046*
X0787239Y0651422*
X0787593Y0650892*
X0788122Y0650539*
X0788746Y0650415*
X078937Y0650539*
X0789899Y0650892*
X0790253Y0651422*
X0790377Y0652046*
X0790253Y065267*
X0789899Y0653199*
X078937Y0653553*
X0788746Y0653677*
G37*
G36*
X10055Y0653131D02*
X1004876Y0653007D01*
X1004346Y0652654*
X1003993Y0652124*
X1003869Y06515*
X1003993Y0650876*
X1004346Y0650347*
X1004876Y0649993*
X10055Y0649869*
X1006124Y0649993*
X1006653Y0650347*
X1007007Y0650876*
X1007131Y06515*
X1007007Y0652124*
X1006653Y0652654*
X1006124Y0653007*
X10055Y0653131*
G37*
G36*
X09855D02*
X0984876Y0653007D01*
X0984346Y0652654*
X0983993Y0652124*
X0983869Y06515*
X0983993Y0650876*
X0984346Y0650347*
X0984876Y0649993*
X09855Y0649869*
X0986124Y0649993*
X0986654Y0650347*
X0987007Y0650876*
X0987131Y06515*
X0987007Y0652124*
X0986654Y0652654*
X0986124Y0653007*
X09855Y0653131*
G37*
G36*
X08265Y0652631D02*
X0825876Y0652507D01*
X0825346Y0652153*
X0824993Y0651624*
X0824869Y0651*
X0824993Y0650376*
X0825346Y0649847*
X0825876Y0649493*
X08265Y0649369*
X0827124Y0649493*
X0827654Y0649847*
X0828007Y0650376*
X0828131Y0651*
X0828007Y0651624*
X0827654Y0652153*
X0827124Y0652507*
X08265Y0652631*
G37*
G36*
X09825Y0650131D02*
X0981876Y0650007D01*
X0981347Y0649653*
X0980993Y0649124*
X0980869Y06485*
X0980993Y0647876*
X0981347Y0647346*
X0981876Y0646993*
X09825Y0646869*
X0983124Y0646993*
X0983654Y0647346*
X0984007Y0647876*
X0984131Y06485*
X0984007Y0649124*
X0983654Y0649653*
X0983124Y0650007*
X09825Y0650131*
G37*
G36*
X08685D02*
X0867876Y0650007D01*
X0867346Y0649653*
X0866993Y0649124*
X0866869Y06485*
X0866993Y0647876*
X0867346Y0647346*
X0867876Y0646993*
X08685Y0646869*
X0869124Y0646993*
X0869654Y0647346*
X0870007Y0647876*
X0870131Y06485*
X0870007Y0649124*
X0869654Y0649653*
X0869124Y0650007*
X08685Y0650131*
G37*
G36*
X0954Y0646131D02*
X0953376Y0646007D01*
X0952847Y0645653*
X0952493Y0645124*
X0952369Y06445*
X0952493Y0643876*
X0952847Y0643347*
X0953376Y0642993*
X0954Y0642869*
X0954624Y0642993*
X0955153Y0643347*
X0955507Y0643876*
X0955631Y06445*
X0955507Y0645124*
X0955153Y0645653*
X0954624Y0646007*
X0954Y0646131*
G37*
G36*
X08437Y0645731D02*
X0843076Y0645607D01*
X0842546Y0645254*
X0842193Y0644724*
X0842069Y06441*
X0842193Y0643476*
X0842546Y0642946*
X0843076Y0642593*
X08437Y0642469*
X0844324Y0642593*
X0844853Y0642946*
X0845207Y0643476*
X0845331Y06441*
X0845207Y0644724*
X0844853Y0645254*
X0844324Y0645607*
X08437Y0645731*
G37*
G36*
X06999Y0645031D02*
X0699276Y0644907D01*
X0698746Y0644554*
X0698393Y0644024*
X0698269Y06434*
X0698393Y0642776*
X0698746Y0642246*
X0699276Y0641893*
X06999Y0641769*
X0700524Y0641893*
X0701053Y0642246*
X0701407Y0642776*
X0701531Y06434*
X0701407Y0644024*
X0701053Y0644554*
X0700524Y0644907*
X06999Y0645031*
G37*
G36*
X08074Y0643191D02*
X0806776Y0643067D01*
X0806246Y0642713*
X0805893Y0642184*
X0805769Y064156*
X0805893Y0640936*
X0805901Y0640923*
X0805708Y0640633*
X0805571Y0640518*
X0805Y0640631*
X0804376Y0640507*
X0803846Y0640154*
X0803493Y0639624*
X0803369Y0639*
X0803493Y0638376*
X0803846Y0637847*
X0804376Y0637493*
X0805Y0637369*
X0805624Y0637493*
X0806153Y0637847*
X0806507Y0638376*
X0806631Y0639*
X0806507Y0639624*
X0806499Y0639637*
X0806692Y0639927*
X0806829Y0640042*
X08074Y0639929*
X0808024Y0640053*
X0808554Y0640407*
X0808907Y0640936*
X0809031Y064156*
X0808907Y0642184*
X0808554Y0642713*
X0808024Y0643067*
X08074Y0643191*
G37*
G36*
X0939744Y0643157D02*
X093912Y0643033D01*
X093859Y064268*
X0938237Y064215*
X0938113Y0641526*
X0938237Y0640902*
X0938536Y0640453*
X0938153Y0640154*
X0937624Y0640507*
X0937Y0640631*
X0936376Y0640507*
X0935847Y0640154*
X0935493Y0639624*
X0935369Y0639*
X0935493Y0638376*
X0935847Y0637847*
X0936376Y0637493*
X0937Y0637369*
X0937518Y0637472*
X0937822Y0637254*
X0937944Y0637105*
X0937869Y0636726*
X0937993Y0636102*
X0938218Y0635764*
X0938282Y0635669*
X0937921Y0635309*
X0937844Y063536*
X0937624Y0635507*
X0937Y0635631*
X0936376Y0635507*
X0935847Y0635153*
X0935493Y0634624*
X0935369Y0634*
X0935493Y0633376*
X0935847Y0632846*
X0936376Y0632493*
X0937Y0632369*
X0937624Y0632493*
X0938153Y0632846*
X0938507Y0633376*
X0938631Y0634*
X0938507Y0634624*
X0938282Y0634962*
X0938218Y0635057*
X0938579Y0635417*
X0938656Y0635366*
X0938876Y0635219*
X09395Y0635095*
X0940124Y0635219*
X0940654Y0635572*
X0941007Y0636102*
X0941131Y0636726*
X0941007Y063735*
X0940654Y063788*
X0940124Y0638233*
X09395Y0638357*
X0938982Y0638254*
X0938678Y0638472*
X0938556Y0638621*
X0938631Y0639*
X0938507Y0639624*
X0938208Y0640073*
X093859Y0640372*
X093912Y0640019*
X0939744Y0639895*
X0940368Y0640019*
X0940897Y0640373*
X0941251Y0640902*
X0941375Y0641526*
X0941251Y064215*
X0940897Y064268*
X0940368Y0643033*
X0939744Y0643157*
G37*
G36*
X0619Y0649931D02*
X0617745Y0649807D01*
X0616539Y0649441*
X0615427Y0648847*
X0614453Y0648047*
X0613653Y0647073*
X0613059Y0645961*
X0612693Y0644755*
X0612569Y06435*
X0612693Y0642245*
X0613059Y0641039*
X0613653Y0639927*
X0614453Y0638953*
X0615427Y0638153*
X0616539Y0637559*
X0617745Y0637193*
X0619Y0637069*
X0620255Y0637193*
X0621461Y0637559*
X0622573Y0638153*
X0623547Y0638953*
X0624347Y0639927*
X0624941Y0641039*
X0625307Y0642245*
X0625431Y06435*
X0625307Y0644755*
X0624941Y0645961*
X0624347Y0647073*
X0623547Y0648047*
X0622573Y0648847*
X0621461Y0649441*
X0620255Y0649807*
X0619Y0649931*
G37*
G36*
X08019Y0638191D02*
X0801276Y0638067D01*
X0800747Y0637713*
X0800393Y0637184*
X0800269Y063656*
X0800393Y0635936*
X0800401Y0635923*
X0800208Y0635633*
X0800071Y0635518*
X07995Y0635631*
X0798876Y0635507*
X0798347Y0635153*
X0797993Y0634624*
X0797869Y0634*
X0797993Y0633376*
X0798347Y0632846*
X0798876Y0632493*
X07995Y0632369*
X0800124Y0632493*
X0800653Y0632846*
X0801007Y0633376*
X0801131Y0634*
X0801007Y0634624*
X0800999Y0634637*
X0801192Y0634927*
X0801329Y0635042*
X08019Y0634929*
X0802524Y0635053*
X0803053Y0635406*
X0803407Y0635936*
X0803531Y063656*
X0803407Y0637184*
X0803053Y0637713*
X0802524Y0638067*
X08019Y0638191*
G37*
G36*
X07556Y0633931D02*
X0754976Y0633807D01*
X0754447Y0633454*
X0754093Y0632924*
X0753969Y06323*
X0754093Y0631676*
X0754447Y0631146*
X0754976Y0630793*
X07556Y0630669*
X0756224Y0630793*
X0756753Y0631146*
X0757107Y0631676*
X0757231Y06323*
X0757107Y0632924*
X0756753Y0633454*
X0756224Y0633807*
X07556Y0633931*
G37*
G36*
X08493Y0633631D02*
X0848676Y0633507D01*
X0848147Y0633153*
X0847793Y0632624*
X0847669Y0632*
X0847793Y0631376*
X0848147Y0630847*
X0848676Y0630493*
X08493Y0630369*
X0849924Y0630493*
X0850453Y0630847*
X0850807Y0631376*
X0850931Y0632*
X0850807Y0632624*
X0850453Y0633153*
X0849924Y0633507*
X08493Y0633631*
G37*
G36*
X0768699Y0633297D02*
X0767964Y0633151D01*
X0767341Y0632735*
X0766925Y0632112*
X0766779Y0631377*
X0766925Y0630642*
X0767341Y0630019*
X0767964Y0629603*
X0768699Y0629457*
X0769434Y0629603*
X0770057Y0630019*
X0770473Y0630642*
X0770619Y0631377*
X0770473Y0632112*
X0770057Y0632735*
X0769434Y0633151*
X0768699Y0633297*
G37*
G36*
X095619Y0633293D02*
X0955455Y0633147D01*
X0954832Y0632731*
X0954416Y0632108*
X095427Y0631373*
X0954416Y0630638*
X0954832Y0630015*
X0955455Y0629599*
X095619Y0629453*
X0956925Y0629599*
X0957548Y0630015*
X0957964Y0630638*
X095811Y0631373*
X0957964Y0632108*
X0957548Y0632731*
X0956925Y0633147*
X095619Y0633293*
G37*
G36*
X08197Y0631831D02*
X0819076Y0631707D01*
X0818546Y0631354*
X0818193Y0630824*
X0818069Y06302*
X0818193Y0629576*
X0818546Y0629046*
X0819076Y0628693*
X08197Y0628569*
X0820324Y0628693*
X0820854Y0629046*
X0821207Y0629576*
X0821331Y06302*
X0821207Y0630824*
X0820854Y0631354*
X0820324Y0631707*
X08197Y0631831*
G37*
G36*
X07782Y0631731D02*
X0777576Y0631607D01*
X0777046Y0631253*
X0776693Y0630724*
X0776569Y06301*
X0776693Y0629476*
X0777046Y0628946*
X0777576Y0628593*
X07782Y0628469*
X0778824Y0628593*
X0779354Y0628946*
X0779707Y0629476*
X0779831Y06301*
X0779707Y0630724*
X0779354Y0631253*
X0778824Y0631607*
X07782Y0631731*
G37*
G36*
X08692Y0600131D02*
X0868576Y0600007D01*
X0868046Y0599653*
X0867778Y0599251*
X0867671Y0599223*
X0867329*
X0867222Y0599251*
X0866953Y0599653*
X0866424Y0600007*
X08658Y0600131*
X0865176Y0600007*
X0864647Y0599653*
X0864293Y0599124*
X0864169Y05985*
X0863707Y0598424*
X0863354Y0598953*
X0862824Y0599307*
X08622Y0599431*
X0861576Y0599307*
X0861047Y0598953*
X0860804Y059859*
X0860602Y0598564*
X0860261Y0598599*
X0860256Y0598601*
X0859953Y0599053*
X0859424Y0599407*
X08588Y0599531*
X0858176Y0599407*
X0857646Y0599053*
X0857293Y0598524*
X0857169Y05979*
X0857293Y0597276*
X0857646Y0596746*
X0858176Y0596393*
X08588Y0596269*
X0859424Y0596393*
X0859953Y0596746*
X0860196Y059711*
X0860398Y0597136*
X0860739Y0597101*
X0860744Y0597099*
X0861047Y0596646*
X0861576Y0596293*
X08622Y0596169*
X0862824Y0596293*
X0863354Y0596646*
X0863707Y0597176*
X0863831Y05978*
X0864293Y0597876*
X0864647Y0597346*
X0865176Y0596993*
X08658Y0596869*
X0866424Y0596993*
X0866953Y0597346*
X0867222Y0597749*
X0867329Y0597777*
X0867671*
X0867778Y0597749*
X0868046Y0597346*
X0868439Y0597084*
X0868501Y0596638*
X0868474Y0596505*
X0868246Y0596353*
X0867893Y0595824*
X0867769Y05952*
X0867893Y0594576*
X0868246Y0594046*
X0868776Y0593693*
X08694Y0593569*
X0870024Y0593693*
X0870553Y0594046*
X0870658Y0594203*
X0871189Y0594097*
X0871193Y0594076*
X0871546Y0593546*
X0872076Y0593193*
X08727Y0593069*
X0873324Y0593193*
X0873853Y0593546*
X0874207Y0594076*
X0874331Y05947*
X0874207Y0595324*
X0873853Y0595854*
X0873324Y0596207*
X08727Y0596331*
X0872076Y0596207*
X0871546Y0595854*
X0871442Y0595697*
X0870911Y0595803*
X0870907Y0595824*
X0870553Y0596353*
X087016Y0596616*
X0870098Y0597062*
X0870126Y0597195*
X0870354Y0597346*
X0870707Y0597876*
X0870831Y05985*
X0870707Y0599124*
X0870354Y0599653*
X0869824Y0600007*
X08692Y0600131*
G37*
G36*
X0873525Y0600808D02*
X0872901Y0600684D01*
X0872372Y0600331*
X0872018Y0599801*
X0871894Y0599177*
X0872018Y0598553*
X0872372Y0598024*
X0872901Y059767*
X0873525Y0597546*
X087415Y059767*
X0874434Y059786*
X0874986Y0597652*
X0875025Y0597457*
X0875378Y0596928*
X0875908Y0596574*
X0876532Y059645*
X0877156Y0596574*
X0877685Y0596928*
X0877953Y0597328*
X0878473Y0597273*
X0878493Y0597176*
X0878846Y0596646*
X0879376Y0596293*
X088Y0596169*
X0880624Y0596293*
X0881153Y0596646*
X0881507Y0597176*
X0881577Y0597527*
X0882108Y0597774*
X0882317Y0597634*
X0882941Y059751*
X0883565Y0597634*
X0884095Y0597987*
X0884448Y0598517*
X0884572Y0599141*
X0884448Y0599765*
X0884095Y0600294*
X0883565Y0600648*
X0882941Y0600772*
X0882317Y0600648*
X0881787Y0600294*
X0881434Y0599765*
X0881364Y0599414*
X0880833Y0599167*
X0880624Y0599307*
X088Y0599431*
X0879376Y0599307*
X0878846Y0598953*
X0878579Y0598553*
X0878058Y0598608*
X0878039Y0598705*
X0877685Y0599235*
X0877156Y0599588*
X0876532Y0599713*
X0875908Y0599588*
X0875622Y0599398*
X0875071Y0599607*
X0875033Y0599801*
X0874679Y0600331*
X087415Y0600684*
X0873525Y0600808*
G37*
G36*
X089807Y0598173D02*
X0897335Y0598027D01*
X0896712Y0597611*
X0896296Y0596988*
X089615Y0596253*
X0896296Y0595518*
X0896712Y0594895*
X0897335Y0594479*
X089807Y0594333*
X0898805Y0594479*
X0899428Y0594895*
X0899844Y0595518*
X089999Y0596253*
X0899844Y0596988*
X0899428Y0597611*
X0898805Y0598027*
X089807Y0598173*
G37*
G36*
X081933D02*
X0818595Y0598027D01*
X0817972Y0597611*
X0817556Y0596988*
X081741Y0596253*
X0817556Y0595518*
X0817972Y0594895*
X0818595Y0594479*
X081933Y0594333*
X0820065Y0594479*
X0820688Y0594895*
X0821104Y0595518*
X082125Y0596253*
X0821104Y0596988*
X0820688Y0597611*
X0820065Y0598027*
X081933Y0598173*
G37*
G36*
X08469Y0595731D02*
X0846276Y0595607D01*
X0845747Y0595254*
X0845393Y0594724*
X0845269Y05941*
X0845393Y0593476*
X0845747Y0592946*
X0846276Y0592593*
X08469Y0592469*
X0847524Y0592593*
X0848053Y0592946*
X0848407Y0593476*
X0848531Y05941*
X0848407Y0594724*
X0848053Y0595254*
X0847524Y0595607*
X08469Y0595731*
G37*
G36*
X06995Y0592631D02*
X0698876Y0592507D01*
X0698347Y0592154*
X0697993Y0591624*
X0697869Y0591*
X0697993Y0590376*
X0698347Y0589847*
X0698876Y0589493*
X06995Y0589369*
X0700124Y0589493*
X0700654Y0589847*
X0701007Y0590376*
X0701131Y0591*
X0701007Y0591624*
X0700654Y0592154*
X0700124Y0592507*
X06995Y0592631*
G37*
G36*
X096081Y0598761D02*
X0959496Y0598631D01*
X0958232Y0598248*
X0957067Y0597625*
X0956046Y0596787*
X0955208Y0595766*
X0954585Y0594601*
X0954202Y0593337*
X0954072Y0592023*
X0954202Y0590708*
X0954585Y0589444*
X0955208Y058828*
X0956046Y0587259*
X0957067Y0586421*
X0958232Y0585798*
X0959496Y0585415*
X096081Y0585285*
X0962125Y0585415*
X0963389Y0585798*
X0964553Y0586421*
X0965574Y0587259*
X0966412Y058828*
X0967035Y0589444*
X0967418Y0590708*
X0967548Y0592023*
X0967418Y0593337*
X0967035Y0594601*
X0966412Y0595766*
X0965574Y0596787*
X0964553Y0597625*
X0963389Y0598248*
X0962125Y0598631*
X096081Y0598761*
G37*
G36*
X076431D02*
X0762995Y0598631D01*
X0761731Y0598248*
X0760567Y0597625*
X0759546Y0596787*
X0758708Y0595766*
X0758085Y0594601*
X0757701Y0593337*
X0757572Y0592023*
X0757701Y0590708*
X0758085Y0589444*
X0758708Y058828*
X0759546Y0587259*
X0760567Y0586421*
X0761731Y0585798*
X0762995Y0585415*
X076431Y0585285*
X0765625Y0585415*
X0766889Y0585798*
X0768053Y0586421*
X0769074Y0587259*
X0769912Y058828*
X0770535Y0589444*
X0770919Y0590708*
X0771048Y0592023*
X0770919Y0593337*
X0770535Y0594601*
X0769912Y0595766*
X0769074Y0596787*
X0768053Y0597625*
X0766889Y0598248*
X0765625Y0598631*
X076431Y0598761*
G37*
G36*
X1156831Y0594045D02*
X1155643Y0593888D01*
X1154536Y059343*
X1153586Y0592701*
X1152857Y059175*
X1152398Y0590643*
X1152242Y0589456*
X1152398Y0588268*
X1152857Y0587161*
X1153586Y058621*
X1154536Y0585481*
X1155643Y0585023*
X1156831Y0584866*
X1158019Y0585023*
X1159126Y0585481*
X1160076Y058621*
X1160805Y0587161*
X1161264Y0588268*
X116142Y0589456*
X1161264Y0590643*
X1160805Y059175*
X1160076Y0592701*
X1159126Y059343*
X1158019Y0593888*
X1156831Y0594045*
G37*
G36*
X0996988D02*
X0995801Y0593888D01*
X0994694Y059343*
X0993743Y0592701*
X0993014Y059175*
X0992556Y0590643*
X0992399Y0589456*
X0992556Y0588268*
X0993014Y0587161*
X0993743Y058621*
X0994694Y0585481*
X0995801Y0585023*
X0996988Y0584866*
X0998176Y0585023*
X0999283Y0585481*
X1000234Y058621*
X1000963Y0587161*
X1001421Y0588268*
X1001578Y0589456*
X1001421Y0590643*
X1000963Y059175*
X1000234Y0592701*
X0999283Y059343*
X0998176Y0593888*
X0996988Y0594045*
G37*
G36*
X0619Y0597431D02*
X0617745Y0597307D01*
X0616539Y0596941*
X0615427Y0596347*
X0614453Y0595547*
X0613653Y0594573*
X0613059Y0593461*
X0612693Y0592255*
X0612569Y0591*
X0612693Y0589745*
X0613059Y0588539*
X0613653Y0587427*
X0614453Y0586453*
X0615427Y0585653*
X0616539Y0585059*
X0617745Y0584693*
X0619Y0584569*
X0620255Y0584693*
X0621461Y0585059*
X0622573Y0585653*
X0623547Y0586453*
X0624347Y0587427*
X0624941Y0588539*
X0625307Y0589745*
X0625431Y0591*
X0625307Y0592255*
X0624941Y0593461*
X0624347Y0594573*
X0623547Y0595547*
X0622573Y0596347*
X0621461Y0596941*
X0620255Y0597307*
X0619Y0597431*
G37*
G36*
X0888285Y0584882D02*
X0887661Y0584758D01*
X0887131Y0584405*
X0886778Y0583875*
X0886769Y0583832*
X0886648Y0583751*
X0886221Y0583642*
X0885824Y0583907*
X08852Y0584031*
X0884576Y0583907*
X0884046Y0583554*
X0883693Y0583024*
X0883569Y05824*
X0883693Y0581776*
X0884046Y0581247*
X0884576Y0580893*
X08852Y0580769*
X0885824Y0580893*
X0886353Y0581247*
X0886707Y0581776*
X0886716Y0581819*
X0886836Y05819*
X0887263Y0582009*
X0887661Y0581744*
X0888285Y058162*
X0888909Y0581744*
X0889438Y0582097*
X0889792Y0582627*
X0889916Y0583251*
X0889792Y0583875*
X0889438Y0584405*
X0888909Y0584758*
X0888285Y0584882*
G37*
G36*
X08616Y0583331D02*
X0860976Y0583207D01*
X0860446Y0582854*
X0860178Y0582451*
X0860071Y0582423*
X0859729*
X0859622Y0582451*
X0859354Y0582854*
X0858824Y0583207*
X08582Y0583331*
X0857576Y0583207*
X0857047Y0582854*
X0856693Y0582324*
X0856569Y05817*
X0856693Y0581076*
X0857047Y0580547*
X0857576Y0580193*
X08582Y0580069*
X0858824Y0580193*
X0859354Y0580547*
X0859622Y0580949*
X0859729Y0580977*
X0860071*
X0860178Y0580949*
X0860446Y0580547*
X0860976Y0580193*
X08616Y0580069*
X0862224Y0580193*
X0862753Y0580547*
X0863107Y0581076*
X0863231Y05817*
X0863107Y0582324*
X0862753Y0582854*
X0862224Y0583207*
X08616Y0583331*
G37*
G36*
X08822Y0580831D02*
X0881576Y0580707D01*
X0881046Y0580353*
X0880693Y0579824*
X0880569Y05792*
X0880693Y0578576*
X0881046Y0578047*
X0881576Y0577693*
X08822Y0577569*
X0882824Y0577693*
X0883354Y0578047*
X0883707Y0578576*
X0883831Y05792*
X0883707Y0579824*
X0883354Y0580353*
X0882824Y0580707*
X08822Y0580831*
G37*
G36*
X08734Y0584331D02*
X0872776Y0584207D01*
X0872246Y0583853*
X0871893Y0583324*
X0871769Y05827*
X0871893Y0582076*
X0872246Y0581546*
X0872776Y0581193*
X08734Y0581069*
X0874024Y0581193*
X0874553Y0581546*
X0874567Y0581567*
X0874729Y058159*
X087514Y0581524*
X0875416Y0581109*
X0875946Y0580756*
X087657Y0580631*
X0877016Y058072*
X0877194Y0580756*
X0877405Y0580327*
X0877147Y0580154*
X0876793Y0579624*
X0876669Y0579*
X0876793Y0578376*
X0877147Y0577846*
X0877676Y0577493*
X08783Y0577369*
X0878924Y0577493*
X0879453Y0577846*
X0879807Y0578376*
X0879931Y0579*
X0879807Y0579624*
X0879453Y0580154*
X0878924Y0580507*
X08783Y0580631*
X0877854Y0580543*
X0877676Y0580507*
X0877464Y0580936*
X0877724Y0581109*
X0878077Y0581638*
X0878201Y0582263*
X0878077Y0582887*
X0877724Y0583416*
X0877194Y058377*
X087657Y0583894*
X0875946Y058377*
X0875416Y0583416*
X0875403Y0583396*
X0875241Y0583372*
X087483Y0583439*
X0874553Y0583853*
X0874024Y0584207*
X08734Y0584331*
G37*
G36*
X13206Y0583441D02*
X1318513Y0583277D01*
X1316477Y0582788*
X1314543Y0581987*
X1312758Y0580893*
X1311166Y0579534*
X1309807Y0577942*
X1308713Y0576157*
X1307912Y0574223*
X1307423Y0572187*
X1307259Y05701*
X1307423Y0568013*
X1307912Y0565977*
X1308713Y0564043*
X1309807Y0562258*
X1311166Y0560666*
X1312758Y0559307*
X1314543Y0558213*
X1316477Y0557412*
X1318513Y0556923*
X13206Y0556759*
X1322687Y0556923*
X1324723Y0557412*
X1326657Y0558213*
X1328442Y0559307*
X1330034Y0560666*
X1331393Y0562258*
X1332487Y0564043*
X1333288Y0565977*
X1333777Y0568013*
X1333941Y05701*
X1333777Y0572187*
X1333288Y0574223*
X1332487Y0576157*
X1331393Y0577942*
X1330034Y0579534*
X1328442Y0580893*
X1326657Y0581987*
X1324723Y0582788*
X1322687Y0583277*
X13206Y0583441*
G37*
G36*
X08369Y0545031D02*
X0836276Y0544907D01*
X0836098Y0544788*
X08357Y0544578*
X0835302Y0544788*
X0835124Y0544907*
X08345Y0545031*
X0833876Y0544907*
X0833346Y0544554*
X0832993Y0544024*
X0832869Y05434*
X0832993Y0542776*
X0833346Y0542246*
X0833876Y0541893*
X08345Y0541769*
X0835124Y0541893*
X0835302Y0542012*
X08357Y0542222*
X0836098Y0542012*
X0836276Y0541893*
X08369Y0541769*
X0837524Y0541893*
X0838054Y0542246*
X0838407Y0542776*
X0838531Y05434*
X0838407Y0544024*
X0838054Y0544554*
X0837524Y0544907*
X08369Y0545031*
G37*
G36*
X08845Y0541531D02*
X0883876Y0541407D01*
X0883346Y0541053*
X0883011Y0540552*
X0882798Y0540524*
X0882702*
X0882489Y0540552*
X0882154Y0541053*
X0881624Y0541407*
X0881Y0541531*
X0880376Y0541407*
X0879846Y0541053*
X0879493Y0540524*
X0879369Y05399*
X0879493Y0539276*
X0879846Y0538747*
X0880376Y0538393*
X0881Y0538269*
X0881624Y0538393*
X0882154Y0538747*
X0882489Y0539248*
X0882702Y0539276*
X0882798*
X0883011Y0539248*
X0883346Y0538747*
X0883876Y0538393*
X08845Y0538269*
X0885124Y0538393*
X0885653Y0538747*
X0886007Y0539276*
X0886131Y05399*
X0886007Y0540524*
X0885653Y0541053*
X0885124Y0541407*
X08845Y0541531*
G37*
G36*
X0846Y0541831D02*
X0845376Y0541707D01*
X0844847Y0541354*
X0844493Y0540824*
X0844369Y05402*
X0844493Y0539576*
X0844847Y0539046*
X0845376Y0538693*
X0846Y0538569*
X0846624Y0538693*
X0847153Y0539046*
X0847507Y0539576*
X0847631Y05402*
X0847507Y0540824*
X0847153Y0541354*
X0846624Y0541707*
X0846Y0541831*
G37*
G36*
X08655Y0541731D02*
X0864876Y0541607D01*
X0864347Y0541254*
X0863993Y0540724*
X0863869Y05401*
X0863993Y0539476*
X0864347Y0538946*
X0864876Y0538593*
X08655Y0538469*
X0866124Y0538593*
X0866654Y0538946*
X0867007Y0539476*
X0867131Y05401*
X0867007Y0540724*
X0866654Y0541254*
X0866124Y0541607*
X08655Y0541731*
G37*
G36*
X08502D02*
X0849576Y0541607D01*
X0849047Y0541254*
X0848693Y0540724*
X0848569Y05401*
X0848693Y0539476*
X0849047Y0538946*
X0849576Y0538593*
X08502Y0538469*
X0850824Y0538593*
X0851353Y0538946*
X0851707Y0539476*
X0851831Y05401*
X0851707Y0540724*
X0851353Y0541254*
X0850824Y0541607*
X08502Y0541731*
G37*
G36*
X0901Y0541631D02*
X0900376Y0541507D01*
X0899846Y0541153*
X0899493Y0540624*
X0899369Y054*
X0899493Y0539376*
X0899846Y0538846*
X0900376Y0538493*
X0901Y0538369*
X0901624Y0538493*
X0902153Y0538846*
X0902507Y0539376*
X0902631Y054*
X0902507Y0540624*
X0902153Y0541153*
X0901624Y0541507*
X0901Y0541631*
G37*
G36*
X08695D02*
X0868876Y0541507D01*
X0868347Y0541153*
X0867993Y0540624*
X0867869Y054*
X0867993Y0539376*
X0868347Y0538846*
X0868876Y0538493*
X08695Y0538369*
X0870124Y0538493*
X0870654Y0538846*
X0871007Y0539376*
X0871131Y054*
X0871007Y0540624*
X0870654Y0541153*
X0870124Y0541507*
X08695Y0541631*
G37*
G36*
X0897Y0541431D02*
X0896376Y0541307D01*
X0895846Y0540953*
X0895493Y0540424*
X0895369Y05398*
X0895493Y0539176*
X0895846Y0538647*
X0896376Y0538293*
X0897Y0538169*
X0897624Y0538293*
X0898153Y0538647*
X0898507Y0539176*
X0898631Y05398*
X0898507Y0540424*
X0898153Y0540953*
X0897624Y0541307*
X0897Y0541431*
G37*
G36*
X0786221Y0530765D02*
X0785596Y0530641D01*
X0785236Y0530401*
X0784876Y0530641*
X0784252Y0530765*
X0783628Y0530641*
X0783268Y0530401*
X0782908Y0530641*
X0782283Y0530765*
X0781659Y0530641*
X078113Y0530287*
X0780776Y0529758*
X0780652Y0529134*
X0780776Y052851*
X078113Y052798*
X078131Y052786*
Y0527258*
X078113Y0527138*
X0780776Y0526609*
X0780652Y0525984*
X0780776Y052536*
X078113Y0524831*
X0781659Y0524477*
X0782283Y0524353*
X0782908Y0524477*
X0783268Y0524718*
X0783628Y0524477*
X0784252Y0524353*
X0784876Y0524477*
X0785236Y0524718*
X0785596Y0524477*
X0786221Y0524353*
X0786845Y0524477*
X0787374Y0524831*
X0787728Y052536*
X0787852Y0525984*
X0787728Y0526609*
X0787374Y0527138*
X0787193Y0527258*
Y052786*
X0787374Y052798*
X0787728Y052851*
X0787852Y0529134*
X0787728Y0529758*
X0787374Y0530287*
X0786845Y0530641*
X0786221Y0530765*
G37*
G36*
X0876Y0530631D02*
X0875376Y0530507D01*
X0875198Y0530388*
X08748Y0530178*
X0874402Y0530388*
X0874224Y0530507*
X08736Y0530631*
X0872976Y0530507*
X0872447Y0530154*
X0872093Y0529624*
X0871969Y0529*
X0872093Y0528376*
X0872447Y0527846*
X0872976Y0527493*
X08736Y0527369*
X0874224Y0527493*
X0874402Y0527612*
X08748Y0527822*
X0875198Y0527612*
X0875376Y0527493*
X0876Y0527369*
X0876624Y0527493*
X0877153Y0527846*
X0877507Y0528376*
X0877631Y0529*
X0877507Y0529624*
X0877153Y0530154*
X0876624Y0530507*
X0876Y0530631*
G37*
G36*
X08922Y0530331D02*
X0891576Y0530207D01*
X0891398Y0530088*
X0891Y0529878*
X0890602Y0530088*
X0890424Y0530207*
X08898Y0530331*
X0889176Y0530207*
X0888647Y0529853*
X0888293Y0529324*
X0888169Y05287*
X0888293Y0528076*
X0888647Y0527547*
X0889176Y0527193*
X08898Y0527069*
X0890424Y0527193*
X0890602Y0527312*
X0891Y0527522*
X0891398Y0527312*
X0891576Y0527193*
X08922Y0527069*
X0892824Y0527193*
X0893353Y0527547*
X0893707Y0528076*
X0893831Y05287*
X0893707Y0529324*
X0893353Y0529853*
X0892824Y0530207*
X08922Y0530331*
G37*
G36*
X0810236Y0530765D02*
X0809612Y0530641D01*
X0809083Y0530287*
X0808729Y0529758*
X080872Y052971*
X080821*
X08082Y0529758*
X0807847Y0530287*
X0807317Y0530641*
X0806693Y0530765*
X0806069Y0530641*
X0805539Y0530287*
X0805186Y0529758*
X0805062Y0529134*
X0805186Y052851*
X0805539Y052798*
X080572Y052786*
Y0527258*
X0805539Y0527138*
X0805186Y0526609*
X0805062Y0525984*
X0805186Y052536*
X0805539Y0524831*
X0806069Y0524477*
X0806693Y0524353*
X0807317Y0524477*
X0807847Y0524831*
X08082Y052536*
X080821Y0525408*
X080872*
X0808729Y052536*
X0809083Y0524831*
X0809612Y0524477*
X0810236Y0524353*
X0810861Y0524477*
X081139Y0524831*
X0811743Y052536*
X0811868Y0525984*
X0811743Y0526609*
X081139Y0527138*
X0811209Y0527258*
Y052786*
X081139Y052798*
X0811743Y052851*
X0811868Y0529134*
X0811743Y0529758*
X081139Y0530287*
X0810861Y0530641*
X0810236Y0530765*
G37*
G36*
X08422Y0530131D02*
X0841576Y0530007D01*
X0841398Y0529888*
X0841Y0529678*
X0840602Y0529888*
X0840424Y0530007*
X08398Y0530131*
X0839176Y0530007*
X0838647Y0529654*
X0838293Y0529124*
X0838169Y05285*
X0838293Y0527876*
X0838647Y0527347*
X0839176Y0526993*
X08398Y0526869*
X0840424Y0526993*
X0840602Y0527112*
X0841Y0527322*
X0841398Y0527112*
X0841576Y0526993*
X08422Y0526869*
X0842824Y0526993*
X0843353Y0527347*
X0843707Y0527876*
X0843831Y05285*
X0843707Y0529124*
X0843353Y0529654*
X0842824Y0530007*
X08422Y0530131*
G37*
G36*
X08566Y0530531D02*
X0855976Y0530407D01*
X0855447Y0530054*
X0855093Y0529524*
X0854969Y05289*
X0855093Y0528276*
X0855447Y0527746*
X0855976Y0527393*
X08566Y0527269*
X0857224Y0527393*
X0857701Y0527712*
X085788Y0527766*
X0858267*
X0858346Y0527646*
X0858876Y0527293*
X08595Y0527169*
X0860124Y0527293*
X0860653Y0527646*
X0861007Y0528176*
X0861131Y05288*
X0861007Y0529424*
X0860653Y0529953*
X0860124Y0530307*
X08595Y0530431*
X0858876Y0530307*
X0858399Y0529988*
X085822Y0529934*
X0857833*
X0857753Y0530054*
X0857224Y0530407*
X08566Y0530531*
G37*
G36*
X0814173Y0530765D02*
X0813549Y0530641D01*
X081302Y0530287*
X0812666Y0529758*
X0812542Y0529134*
X0812666Y052851*
X081302Y052798*
X08132Y052786*
Y0527258*
X081302Y0527138*
X0812666Y0526609*
X0812542Y0525984*
X0812666Y052536*
X081302Y0524831*
X0813549Y0524477*
X0814173Y0524353*
X0814797Y0524477*
X0815327Y0524831*
X081568Y052536*
X0815805Y0525984*
X081568Y0526609*
X0815327Y0527138*
X0815146Y0527258*
Y052786*
X0815327Y052798*
X081568Y052851*
X0815805Y0529134*
X081568Y0529758*
X0815327Y0530287*
X0814797Y0530641*
X0814173Y0530765*
G37*
G36*
X06285Y0550641D02*
X0626413Y0550477D01*
X0624377Y0549988*
X0622443Y0549187*
X0620658Y0548093*
X0619066Y0546734*
X0617707Y0545142*
X0616613Y0543357*
X0615812Y0541423*
X0615323Y0539387*
X0615159Y05373*
X0615323Y0535213*
X0615812Y0533177*
X0616613Y0531243*
X0617707Y0529458*
X0619066Y0527866*
X0620658Y0526507*
X0622443Y0525413*
X0624377Y0524612*
X0626413Y0524123*
X06285Y0523959*
X0630587Y0524123*
X0632623Y0524612*
X0634557Y0525413*
X0636342Y0526507*
X0637934Y0527866*
X0639293Y0529458*
X0640387Y0531243*
X0641188Y0533177*
X0641677Y0535213*
X0641841Y05373*
X0641677Y0539387*
X0641188Y0541423*
X0640387Y0543357*
X0639293Y0545142*
X0637934Y0546734*
X0636342Y0548093*
X0634557Y0549187*
X0632623Y0549988*
X0630587Y0550477*
X06285Y0550641*
G37*
%LNgrandmaster-3*%
%LPD*%
G54D140*
X0609Y0601D03*
Y0581D03*
X0629D03*
Y0601D03*
X0609Y07585D03*
Y07385D03*
X0629D03*
Y07585D03*
X0609Y0706D03*
Y0686D03*
X0629D03*
Y0706D03*
X0609Y06535D03*
Y06335D03*
X0629D03*
Y06535D03*
G54D155*
X0996988Y0749298D03*
X1156831Y0669377D03*
G54D156*
X1255965Y0859346D03*
X12725Y0881D03*
X1289035Y0859346D03*
G54D158*
X1211Y0906D03*
G54D159*
X1192496Y0894189D03*
G54D165*
X090876Y0524705D03*
X0894587Y0525591D03*
X0853622Y0524878D03*
X0843701Y0525D03*
X079063Y052487D03*
X08025Y0525D03*
X0862703Y0525184D03*
X0878937Y0525591D03*
X083Y0525D03*
X0887205Y0525689D03*
X0891732Y0814961D03*
X0885827D03*
X0883071D03*
X0888976D03*
X0891732Y0811811D03*
X0885827D03*
X0883071D03*
X0888976D03*
X0891732Y081811D03*
X0885827D03*
X0883071D03*
X0888976D03*
Y082126D03*
X0883071D03*
X0885827D03*
X0891732D03*
X1224409Y0791339D03*
X126378Y0813386D03*
X1033Y07729D03*
X0940462Y06809D03*
X07779Y09331D03*
X09581Y06666D03*
X08774Y07572D03*
X07712Y06993D03*
X08887Y08382D03*
X08505Y05941D03*
X08656Y06096D03*
X09821Y08766D03*
X08314Y0759D03*
X07662Y06796D03*
X08774Y06098D03*
X09386Y09226D03*
X10263Y08139D03*
X0971Y07D03*
X09401Y0671759D03*
X07705Y06599D03*
X1085Y08D03*
X0813Y08742D03*
X08479Y07417D03*
X08401Y06093D03*
X1012Y0852D03*
X0903536Y0821364D03*
X10199Y08139D03*
X09585Y06518D03*
X08676Y07572D03*
X07662Y06403D03*
X12617Y08036D03*
X10143Y08139D03*
X10055Y07726D03*
X08715Y08525D03*
X08302Y05938D03*
X08862Y07301D03*
X07666Y06895D03*
X07239Y07004D03*
X0971Y06925D03*
X09404Y06577D03*
X07712Y06698D03*
X08807Y07907D03*
X08907D03*
X10122Y0669D03*
X08303Y06097D03*
X10059Y08139D03*
X08665Y08505D03*
X10225Y07729D03*
X08714Y07924D03*
X08395Y07416D03*
X09723Y06422D03*
X08577Y07573D03*
X07662Y06501D03*
X09545Y06995D03*
X08961Y08415D03*
X12447Y08013D03*
X07682Y09083D03*
X09633Y0564D03*
X08774Y07433D03*
X07665Y06993D03*
X1003Y08788D03*
X12467Y08235D03*
X10324Y08139D03*
X10468D03*
X09545Y06845D03*
X09397Y06465D03*
X07707Y06403D03*
X07709Y06796D03*
X09188Y08218D03*
X07717Y0933D03*
X08244Y07283D03*
X08924Y05957D03*
X08466Y0746D03*
X07661Y06599D03*
X08892Y06099D03*
X09545Y06945D03*
X09959Y06675D03*
X09951Y07728D03*
X08601Y05938D03*
X08464Y07984D03*
X08676Y07315D03*
X08597Y06095D03*
X07252Y07486D03*
X09709Y06717D03*
X0954Y06417D03*
X08872Y0757D03*
X07709Y06501D03*
X07712Y06894D03*
X08875Y07903D03*
X09987Y06715D03*
X08404Y08299D03*
X10105Y08139D03*
X12639Y08345D03*
X0832Y08365D03*
X08622Y0788D03*
X08879Y09225D03*
X09361Y07892D03*
X084Y07583D03*
X07661Y06698D03*
X08833Y06099D03*
X08753Y07906D03*
X08249Y08745D03*
X08406Y07796D03*
X08572Y07312D03*
X08499Y06094D03*
X0774Y09114D03*
X08281Y09221D03*
X09871Y08113D03*
X09735Y08346D03*
X09708Y08076D03*
X11724Y0856D03*
X11667Y0855D03*
X08405Y05941D03*
X09594Y05686D03*
X08715Y06097D03*
X12619Y06376D03*
X12539Y06535D03*
X12593Y06616D03*
Y06676D03*
Y06726D03*
X12592Y06781D03*
X12676Y06832D03*
X1269Y06885D03*
X13042Y06961D03*
X1294Y07099D03*
X12598Y0718D03*
X12386Y07115D03*
X12039Y07175D03*
X11995Y07438D03*
X12265Y07395D03*
X12389Y07457D03*
X12388Y07505D03*
X12387Y0756D03*
X12388Y07614D03*
X12389Y07661D03*
X123622Y0791339D03*
X10901Y09207D03*
X10378Y0921D03*
X09768Y09027D03*
X10076Y08896D03*
X10185Y08888D03*
X10422Y08139D03*
X09321Y08305D03*
X0909Y07916D03*
X09023Y07972D03*
X09009Y07901D03*
X08851Y08791D03*
X08715Y08733D03*
X09522Y08664D03*
X0926Y08792D03*
X07233Y06476D03*
X07247Y05946D03*
X06645Y05794D03*
X06646Y06032D03*
X06645Y06318D03*
X06644Y06555D03*
X06645Y06843D03*
Y07077D03*
Y07369D03*
X0664412Y0759783D03*
M02*